G04 ================== begin FILE IDENTIFICATION RECORD ==================*
G04 Layout Name:  9052_F0T_PDB_Converter_Brick_F_V03_1208_1600.brd*
G04 Film Name:    in1*
G04 File Format:  Gerber RS274X*
G04 File Origin:  Cadence Allegro 17.2-S081*
G04 Origin Date:  Wed Dec 21 09:54:58 2022*
G04 *
G04 Layer:  DRAWING FORMAT/TITLE_BLOCK_A*
G04 Layer:  PIN/SPECIAL_DRILL*
G04 Layer:  DRAWING FORMAT/TITLE_BLOCK*
G04 Layer:  VIA CLASS/IN1*
G04 Layer:  PIN/IN1*
G04 Layer:  MANUFACTURING/PHOTOPLOT_OUTLINE*
G04 Layer:  ETCH/IN1*
G04 Layer:  DRAWING FORMAT/TITLE_DATA_IN1*
G04 *
G04 Offset:    (0.00 0.00)*
G04 Mirror:    No*
G04 Mode:      Positive*
G04 Rotation:  0*
G04 FullContactRelief:  No*
G04 UndefLineWidth:     6.00*
G04 ================== end FILE IDENTIFICATION RECORD ====================*
%FSLAX25Y25*MOIN*%
%IR0*IPPOS*OFA0.00000B0.00000*MIA0B0*SFA1.00000B1.00000*%
%ADD10C,.02*%
%AMMACRO19*
4,1,41,-.40714,-.11826,
-.427771,-.11755,
-.447965,-.113268,
-.467108,-.105544,
-.48462,-.094614,
-.499967,-.080809,
-.512684,-.064548,
-.522385,-.046326,
-.528773,-.026697,
-.531656,-.006256,
-.530946,.014374,
-.526664,.034568,
-.518941,.053712,
-.50801,.071223,
-.494205,.086571,
-.477944,.099288,
-.459723,.108988,
-.440093,.115377,
-.419653,.11826,
-.40714,.11826,
.33517,.07906,
.45275,.07906,
.466479,.077859,
.47979,.074292,
.49228,.068468,
.503569,.060563,
.513313,.050819,
.521218,.03953,
.527042,.02704,
.530609,.013729,
.53181,0.0,
.530609,-.013729,
.527042,-.02704,
.521218,-.03953,
.513313,-.050819,
.503569,-.060563,
.49228,-.068468,
.47979,-.074292,
.466479,-.077859,
.45275,-.07906,
.33517,-.07906,
-.40714,-.11826,
0.0*
%
%ADD19MACRO19*%
%ADD15C,.06*%
%ADD14C,.062*%
%ADD12C,.018*%
%ADD20C,.066*%
%ADD17C,.06015*%
%ADD16C,.093*%
%ADD18C,.085*%
%ADD11C,.058*%
%ADD21C,.4*%
%ADD13C,.123*%
%ADD22C,.01*%
%ADD23C,.015*%
%ADD24C,.025*%
%ADD25C,.035*%
%ADD26C,.006*%
%ADD27C,.0051*%
%ADD37C,.03004*%
%ADD40C,.03006*%
%ADD31C,.07004*%
%ADD44C,.06204*%
%ADD38C,.07006*%
%ADD35C,.07204*%
%ADD41C,.07018*%
%ADD39C,.07604*%
%ADD30C,.11004*%
%ADD36C,.11204*%
%ADD33C,.10304*%
%ADD32C,.13304*%
%ADD34C,.14304*%
%ADD29C,.30604*%
%ADD43C,.40406*%
%ADD28C,.16506*%
%ADD42C,.28606*%
G75*
%LPD*%
G75*
G36*
G01X932000Y576740D02*
X1271654D01*
G02X1289339Y559055I0J-17685D01*
G01Y19685D01*
G02X1271654Y2000I-17685J0D01*
G01X19685D01*
G02X2000Y19685I0J17685D01*
G01Y63268D01*
G02X11811Y73079I9811J0D01*
G01X37796D01*
G03X41764Y77047I0J3969D01*
G01Y122323D01*
G03X37796Y126291I-3969J-1D01*
G01X11811D01*
G02X2000Y136102I0J9811D01*
G01Y445787D01*
G02X11811Y455598I9811J0D01*
G01X37795D01*
G03X41764Y459567I0J3969D01*
G01Y504843D01*
G03X37796Y508811I-3969J-1D01*
G01X11811D01*
G02X2000Y518622I0J9811D01*
G01Y559055D01*
G02X19685Y576740I17685J0D01*
G01X142000D01*
Y574742D01*
X19685D01*
G03X3998Y559055I0J-15687D01*
G01Y518622D01*
G03X11811Y510808I7814J0D01*
G01X37796D01*
G02X43761Y504843I0J-5966D01*
G01X43762D01*
Y459567D01*
G02X37795Y453600I-5967J0D01*
G01X11811D01*
G03X3998Y445787I0J-7813D01*
G01Y136102D01*
G03X11811Y128288I7814J0D01*
G01X37796D01*
G02X43761Y122323I-1J-5966D01*
G01X43762D01*
Y77047D01*
X43761D01*
G02X37796Y71082I-5966J1D01*
G01X11811D01*
G03X3998Y63270I0J-7813D01*
G01Y19685D01*
G03X19685Y3998I15687J0D01*
G01X1271654D01*
G03X1287341Y19685I0J15687D01*
G01Y559055D01*
G03X1271654Y574742I-15687J0D01*
G01X932000D01*
Y576740D01*
G37*
G36*
G01X114733Y266750D02*
X151267D01*
G02X151409Y266691I0J-200D01*
G01X154541Y263559D01*
G02X154600Y263417I-141J-142D01*
G01Y251283D01*
G02X154541Y251141I-200J0D01*
G01X130859Y227459D01*
G02X130717Y227400I-142J141D01*
G01X36383D01*
G02X36241Y227459I0J200D01*
G01X33159Y230541D01*
G02X33100Y230683I141J142D01*
G01Y263117D01*
G02X33159Y263259I200J0D01*
G01X34241Y264341D01*
G02X34383Y264400I142J-141D01*
G01X105555D01*
G02X105735Y264287I0J-200D01*
G01X105916Y263909D01*
X105903Y263795D01*
X105867Y263750D01*
G03X105098Y261560I2734J-2190D01*
G03X105398Y260141I3502J-1D01*
G02Y259979I-182J-81D01*
G03X105098Y258560I3202J-1418D01*
G03X105398Y257141I3502J-1D01*
G02Y256979I-182J-81D01*
G03X105098Y255560I3202J-1418D01*
G03X108600Y252058I3502J0D01*
G03X110019Y252358I1J3502D01*
G02X110181I81J-182D01*
G03X111600Y252058I1418J3202D01*
G03X115102Y255560I0J3502D01*
G03X114802Y256979I-3502J1D01*
G02Y257141I182J81D01*
G03X115102Y258560I-3202J1418D01*
G03X114802Y259979I-3502J1D01*
G02Y260141I182J81D01*
G03X115102Y261560I-3202J1418D01*
G03X113267Y264640I-3502J0D01*
G01X113224Y264663D01*
X113171Y264739D01*
X113118Y265104D01*
G02X113174Y265274I198J29D01*
G01X114591Y266691D01*
G02X114733Y266750I142J-141D01*
G37*
G36*
G01X69077Y457591D02*
X124545D01*
G02X124687Y457532I0J-200D01*
G01X134397D01*
G02X134539Y457473I0J-200D01*
G01X136140Y455872D01*
G02X136199Y455730I-141J-142D01*
G01Y318638D01*
G02X136140Y318496I-200J0D01*
G01X85103Y267459D01*
G02X84961Y267400I-142J141D01*
G01X34683D01*
G02X34541Y267459I0J200D01*
G01X33359Y268641D01*
G02X33300Y268783I141J142D01*
G01Y302217D01*
G02X33359Y302359I200J0D01*
G01X36041Y305041D01*
G02X36183Y305100I142J-141D01*
G01X45965D01*
G03X46107Y305159I0J200D01*
G01X66581Y325633D01*
G03X66640Y325775I-141J142D01*
G01Y352507D01*
G02X66656Y352585I200J0D01*
G03Y355339I-3221J1377D01*
G02X66640Y355417I184J78D01*
G01Y455154D01*
G02X66699Y455296I200J0D01*
G01X68935Y457532D01*
G02X69077Y457591I142J-141D01*
G37*
G36*
G01X244183Y288126D02*
X306337D01*
G02X306479Y288067I0J-200D01*
G01X335137Y259409D01*
G03X335279Y259350I142J141D01*
G01X696177D01*
G02X696326Y259283I0J-200D01*
G01X696511Y259076D01*
X696537Y259008D01*
Y258970D01*
G03Y258962I3503J-4D01*
G01Y258960D01*
G03X696553Y258631I3503J5D01*
G02X696554Y258606I-199J-20D01*
G03X696552Y258509I3500J-121D01*
G03X703556I3502J0D01*
G03X703542Y258826I-3502J4D01*
G02X703541Y258850I199J20D01*
G03X703543Y258940I-3501J123D01*
G01Y258977D01*
X703569Y259045D01*
X703782Y259283D01*
G02X703931Y259350I149J-133D01*
G01X713562D01*
G02X713676Y259314I0J-200D01*
G01X713701Y259296D01*
X713738Y259248D01*
X713749Y259219D01*
X713879Y258868D01*
G02X713821Y258646I-188J-70D01*
G03X712598Y255987I2279J-2659D01*
G03X719602I3502J0D01*
G03X718379Y258646I-3502J0D01*
G02X718321Y258868I130J152D01*
G01X718451Y259219D01*
G02X718524Y259314I188J-69D01*
G02X718638Y259350I114J-164D01*
G01X786403D01*
X786515Y259251D01*
X786525Y259175D01*
G03X793475I3475J437D01*
G01X793485Y259251D01*
X793597Y259350D01*
X794249D01*
X794363Y259248D01*
X794371Y259171D01*
G03X797854Y256037I3483J368D01*
G03X800382Y257115I0J3503D01*
G01X800411Y257145D01*
X800486Y257177D01*
X800857Y257176D01*
X800932Y257144D01*
X800960Y257114D01*
G03X803500Y256023I2540J2411D01*
G03X806157Y257244I0J3501D01*
G01X806186Y257278D01*
X806267Y257314D01*
X806664Y257308D01*
X806744Y257269D01*
X806772Y257234D01*
G03X809500Y255928I2728J2196D01*
G03X812992Y259165I0J3502D01*
G02X813191Y259350I199J-15D01*
G01X822563D01*
G02X822568I3J-200D01*
G02X822749Y259224I-5J-200D01*
G03X826000Y257023I3251J1300D01*
G03X828296Y257881I0J3501D01*
G02X828429Y257930I131J-151D01*
G01X828510Y257929D01*
G02X828580Y257916I-1J-200D01*
G01X828677Y257879D01*
X828703Y257856D01*
G03X831000Y256998I2297J2646D01*
G03X833283Y257845I0J3502D01*
G01X833310Y257868D01*
X833407Y257904D01*
G02X833477Y257917I71J-187D01*
G01X833523D01*
G02X833593Y257904I-1J-200D01*
G01X833690Y257868D01*
X833717Y257845D01*
G03X836000Y256998I2283J2655D01*
G01X836001D01*
G03X837794Y257492I0J3502D01*
G01X837853Y257527D01*
X837990Y257510D01*
X840941Y254559D01*
G02X841000Y254417I-141J-142D01*
G01Y188583D01*
G02X840941Y188441I-200J0D01*
G01X836059Y183559D01*
X836031Y183530D01*
X835957Y183500D01*
X801083D01*
G03X800941Y183441I0J-200D01*
G01X798235Y180735D01*
G03X798176Y180593I141J-142D01*
G01Y88162D01*
G02X798117Y88020I-200J0D01*
G01X790175Y80078D01*
X790147Y80049D01*
X790073Y80019D01*
X650683D01*
G03X650541Y79960I0J-200D01*
G01X643559Y72978D01*
G03X643500Y72836I141J-142D01*
G01Y9883D01*
G02X643441Y9741I-200J0D01*
G01X641259Y7559D01*
G02X641117Y7500I-142J141D01*
G01X147066D01*
G02X146924Y7559I0J200D01*
G01X141179Y13304D01*
X141150Y13332D01*
X141120Y13406D01*
Y120314D01*
G02X141179Y120456I200J0D01*
G01X159441Y138718D01*
G03X159500Y138860I-141J142D01*
G01Y231717D01*
G03X159441Y231859I-200J0D01*
G01X158186Y233114D01*
X158150Y233164D01*
G03X156635Y234679I-3116J-1601D01*
G01X156585Y234715D01*
X156300Y235000D01*
X155711D01*
G03X155034Y235066I-677J-3437D01*
G03X154357Y235000I0J-3503D01*
G01X150700D01*
X149350Y236350D01*
Y241750D01*
X153600Y246000D01*
X155500D01*
X156200Y245300D01*
Y243569D01*
G03X155140Y243733I-1059J-3339D01*
G03Y236727I0J-3503D01*
G03X156589Y237041I-1J3503D01*
G03X160017Y234261I3428J724D01*
G03X163081Y236066I0J3503D01*
G02X163701Y236167I350J-194D01*
G03X165775Y235258I2368J2582D01*
G01X165811Y235255D01*
X165874Y235226D01*
X166441Y234659D01*
G03X166583Y234600I142J141D01*
G01X168917D01*
G03X169059Y234659I0J200D01*
G01X175341Y240941D01*
G03X175400Y241083I-141J142D01*
G01Y264231D01*
G02X175459Y264373I200J0D01*
G01X176941Y265855D01*
G02X177083Y265914I142J-141D01*
G01X195109D01*
G02X195112I2J-200D01*
G02X195301Y265770I-3J-200D01*
G03X200197Y262102I4896J1434D01*
G03X203848Y263640I0J5102D01*
G01X203877Y263669D01*
X203950Y263700D01*
X204318D01*
X204391Y263669D01*
X204420Y263640D01*
G03X211722I3651J3564D01*
G01X211751Y263669D01*
X211824Y263700D01*
X212192D01*
X212265Y263669D01*
X212294Y263640D01*
G03X219596I3651J3564D01*
G01X219625Y263669D01*
X219698Y263700D01*
X220066D01*
X220139Y263669D01*
X220168Y263640D01*
G03X227470I3651J3564D01*
G01X227499Y263669D01*
X227572Y263700D01*
X227940D01*
X228013Y263669D01*
X228042Y263640D01*
G03X235344I3651J3564D01*
G01X235373Y263669D01*
X235446Y263700D01*
X235814D01*
X235887Y263669D01*
X235916Y263640D01*
G03X243218I3651J3564D01*
G01X243247Y263669D01*
X243320Y263700D01*
X243688D01*
X243761Y263669D01*
X243790Y263640D01*
G03X247441Y262102I3651J3564D01*
G03X252124Y265179I0J5102D01*
G01X252176Y265300D01*
X252194D01*
Y266511D01*
G03X252135Y266653I-200J0D01*
G01X251613Y267174D01*
X251583Y267244D01*
X251582Y267284D01*
G03X248260Y271264I-4141J-80D01*
G01X248100Y271296D01*
Y271300D01*
X248057D01*
X248043Y271302D01*
G03X247441Y271346I-602J-4098D01*
G03X246839Y271302I0J-4142D01*
G01X246825Y271300D01*
X245383D01*
G02X245241Y271359I0J200D01*
G01X242359Y274241D01*
G02X242300Y274383I141J142D01*
G01Y286243D01*
G02X242359Y286385I200J0D01*
G01X244041Y288067D01*
G02X244183Y288126I142J-141D01*
G37*
G36*
G01X895062Y569699D02*
X1079936D01*
G02X1080078Y569640I0J-200D01*
G01X1082543Y567175D01*
G02X1082602Y567033I-141J-142D01*
G01Y377070D01*
G02X1082506Y376900I-200J1D01*
G01X1082169Y376694D01*
X1082067Y376690D01*
X1082019Y376715D01*
G03X1080418Y377102I-1600J-3115D01*
G03Y370098I0J-3502D01*
G03X1082019Y370485I1J3502D01*
G01X1082067Y370510D01*
X1082169Y370506D01*
X1082506Y370300D01*
G02X1082602Y370130I-104J-171D01*
G01Y245185D01*
G02X1082543Y245043I-200J0D01*
G01X1079059Y241559D01*
G02X1078917Y241500I-142J141D01*
G01X1007883D01*
G02X1007741Y241559I0J200D01*
G01X999059Y250241D01*
G03X998917Y250300I-142J-141D01*
G01X959149D01*
G02X959007Y250359I0J200D01*
G01X956025Y253341D01*
G02X955966Y253483I141J142D01*
G01Y362451D01*
G03X955907Y362593I-200J0D01*
G01X955751Y362749D01*
G02X955692Y362899I141J142D01*
G01X955705Y363235D01*
X955741Y363309D01*
X955774Y363336D01*
G03X957002Y366000I-2274J2663D01*
G03X953500Y369502I-3502J0D01*
G03X952081Y369202I-1J-3502D01*
G02X951919I-81J182D01*
G03X950500Y369502I-1418J-3202D01*
G03X949208Y369255I0J-3503D01*
G02X949135Y369241I-74J186D01*
G01X945365D01*
G02X945292Y369255I1J200D01*
G03X942708I-1292J-3256D01*
G01X942673Y369241D01*
X942327D01*
X942292Y369255D01*
G03X939708I-1292J-3256D01*
G02X939635Y369241I-74J186D01*
G01X935865D01*
G02X935792Y369255I1J200D01*
G03X933208I-1292J-3256D01*
G01X933173Y369241D01*
X932827D01*
X932792Y369255D01*
G03X930208I-1292J-3256D01*
G02X930135Y369241I-74J186D01*
G01X926365D01*
G02X926292Y369255I1J200D01*
G03X923708I-1292J-3256D01*
G01X923673Y369241D01*
X923327D01*
X923292Y369255D01*
G03X920708I-1292J-3256D01*
G02X920635Y369241I-74J186D01*
G01X916865D01*
G02X916792Y369255I1J200D01*
G03X914208I-1292J-3256D01*
G01X914173Y369241D01*
X913827D01*
X913792Y369255D01*
G03X911208I-1292J-3256D01*
G02X911135Y369241I-74J186D01*
G01X907365D01*
G02X907292Y369255I1J200D01*
G03X904708I-1292J-3256D01*
G01X904673Y369241D01*
X904327D01*
X904292Y369255D01*
G03X901708I-1292J-3256D01*
G02X901635Y369241I-74J186D01*
G01X897865D01*
G02X897792Y369255I1J200D01*
G03X895208I-1292J-3256D01*
G01X895173Y369241D01*
X894827D01*
X894792Y369255D01*
G03X892208I-1292J-3256D01*
G02X892135Y369241I-74J186D01*
G01X888365D01*
G02X888292Y369255I1J200D01*
G03X885708I-1292J-3256D01*
G01X885673Y369241D01*
X885327D01*
X885292Y369255D01*
G03X882708I-1292J-3256D01*
G02X882635Y369241I-74J186D01*
G01X878865D01*
G02X878792Y369255I1J200D01*
G03X876208I-1292J-3256D01*
G01X876173Y369241D01*
X875827D01*
X875792Y369255D01*
G03X873208I-1292J-3256D01*
G02X873135Y369241I-74J186D01*
G01X869865D01*
G02X869792Y369255I1J200D01*
G03X867208I-1292J-3256D01*
G01X867173Y369241D01*
X866827D01*
X866792Y369255D01*
G03X864208I-1292J-3256D01*
G02X864135Y369241I-74J186D01*
G01X860865D01*
G02X860792Y369255I1J200D01*
G03X858208I-1292J-3256D01*
G01X858173Y369241D01*
X857827D01*
X857792Y369255D01*
G03X855208I-1292J-3256D01*
G02X855135Y369241I-74J186D01*
G01X851865D01*
G02X851792Y369255I1J200D01*
G03X849208I-1292J-3256D01*
G01X849173Y369241D01*
X848827D01*
X848792Y369255D01*
G03X846208I-1292J-3256D01*
G02X846135Y369241I-74J186D01*
G01X750323D01*
G02X750202Y369282I0J200D01*
G03X745948I-2127J-2782D01*
G02X745827Y369241I-121J159D01*
G01X625074D01*
G03X624932Y369182I0J-200D01*
G01X586059Y330309D01*
G02X585917Y330250I-142J141D01*
G01X149783D01*
G02X149641Y330309I0J200D01*
G01X149159Y330791D01*
G02X149100Y330933I141J142D01*
G01Y456117D01*
G02X149159Y456259I200J0D01*
G01X150341Y457441D01*
G02X150483Y457500I142J-141D01*
G01X721296D01*
G03X721438Y457559I0J200D01*
G01X882686D01*
G03X882828Y457618I0J200D01*
G01X889561Y464351D01*
G03X889620Y464493I-141J142D01*
G01Y564257D01*
G02X889679Y564399I200J0D01*
G01X894920Y569640D01*
G02X895062Y569699I142J-141D01*
G37*
G36*
G01X153583Y570869D02*
X874368D01*
G02X874510Y570810I0J-200D01*
G01X876941Y568379D01*
G02X877000Y568237I-141J-142D01*
G01Y567042D01*
G02X876817Y566843I-200J0D01*
G03Y550397I693J-8223D01*
G02X877000Y550198I-17J-199D01*
G01Y463443D01*
X876970Y463369D01*
X876941Y463341D01*
X874916Y461316D01*
X874888Y461287D01*
X874814Y461257D01*
X761919D01*
G02X761864Y461265I1J200D01*
G01X761839Y461272D01*
X761815Y461286D01*
G03X761710Y461316I-105J-170D01*
G01X149971D01*
G02X149829Y461375I0J200D01*
G01X147822Y463381D01*
G02X147763Y463523I141J142D01*
G01Y558041D01*
G02X147777Y558114I200J-1D01*
G01X147807Y558189D01*
Y558190D01*
G03X147822Y558265I-185J76D01*
G01Y565148D01*
X147852Y565222D01*
X147881Y565250D01*
X153441Y570810D01*
G02X153583Y570869I142J-141D01*
G37*
G36*
G01X1104657Y573112D02*
X1270850D01*
G02X1270883Y573109I-2J-200D01*
G02X1270990Y573055I-32J-197D01*
G01X1285441Y558604D01*
G02X1285500Y558462I-141J-142D01*
G01Y19043D01*
X1285470Y18969D01*
X1285441Y18941D01*
X1272568Y6068D01*
G02X1272426Y6009I-142J141D01*
G01X654574D01*
G02X654432Y6068I0J200D01*
G01X650859Y9641D01*
X650830Y9669D01*
X650800Y9743D01*
Y68917D01*
G02X650857Y69057I200J0D01*
G01X655638Y73838D01*
G02X655640Y73840I142J-140D01*
G02X655780Y73897I140J-143D01*
G01X678736D01*
G03X678812Y73912I0J200D01*
G01X678916Y73956D01*
X791421D01*
G03X791563Y74015I0J200D01*
G01X802510Y84962D01*
G03X802569Y85104I-141J142D01*
G01Y178917D01*
G02X802628Y179059I200J0D01*
G01X804504Y180935D01*
G02X804646Y180994I142J-141D01*
G01X836446D01*
X836457Y180998D01*
X836953D01*
G03X837095Y181057I0J200D01*
G01X837431Y181393D01*
X837465Y181407D01*
X837847Y181802D01*
X842712Y186668D01*
G03X842769Y186730I-1963J1862D01*
G01X842773Y186735D01*
X843443Y187405D01*
G03X843502Y187547I-141J142D01*
G01Y188519D01*
X843503Y188526D01*
G03X843506Y188582I-2698J173D01*
G01Y254418D01*
G03X843503Y254474I-2701J-117D01*
G01X843502Y254481D01*
Y255453D01*
G03X843443Y255595I-200J0D01*
G01X842773Y256265D01*
X842769Y256270D01*
G03X842712Y256332I-2020J-1800D01*
G01X839923Y259121D01*
G02X839910Y259136I144J138D01*
G01X839408Y259751D01*
G03X839277Y259823I-155J-127D01*
G01X839238Y259828D01*
X839201Y259848D01*
G02X839156Y259882I97J175D01*
G01X836761Y262277D01*
G03X836619Y262336I-142J-141D01*
G01X805653D01*
G02X805537Y262373I0J200D01*
G03X803500Y263027I-2038J-2848D01*
G03X801463Y262373I1J-3502D01*
G02X801347Y262336I-116J163D01*
G01X698038D01*
X697988Y262365D01*
X697987Y262366D01*
G03X697885Y262394I-102J-173D01*
G01X339029D01*
X338955Y262424D01*
X338927Y262453D01*
X309578Y291802D01*
G03X309436Y291861I-142J-141D01*
G01X238683D01*
G03X238541Y291802I0J-200D01*
G01X233879Y287139D01*
G03X233820Y286997I141J-142D01*
G01Y274403D01*
G02X233761Y274261I-200J0D01*
G01X231759Y272259D01*
X231731Y272230D01*
X231657Y272200D01*
X201083D01*
G02X200941Y272259I0J200D01*
G01X200455Y272745D01*
X200426Y272773D01*
X200396Y272847D01*
Y276156D01*
G03X200479Y277204I-6577J1048D01*
G03X187159I-6660J0D01*
G03X191316Y271032I6660J0D01*
G02X191386Y270837I-126J-155D01*
G01X191309Y270453D01*
G02X191113Y270292I-196J39D01*
G01X181525D01*
G02X181329Y270453I0J200D01*
G01X181252Y270837D01*
G02X181370Y271061I196J40D01*
G01X181371D01*
G03X185471Y277204I-2552J6143D01*
G03X172167I-6652J0D01*
G03X176266Y271061I6653J0D01*
G01X176268D01*
G02X176386Y270837I-78J-184D01*
G01X176309Y270453D01*
G02X176113Y270292I-196J39D01*
G01X168151D01*
X168077Y270322D01*
X168049Y270351D01*
X165759Y272641D01*
X165730Y272669D01*
X165700Y272743D01*
Y304286D01*
G02X165757Y304426I200J0D01*
G01X187733Y326402D01*
G02X187875Y326461I142J-141D01*
G01X588975D01*
G03X589117Y326520I0J200D01*
G01X619896Y357299D01*
G02X620038Y357358I142J-141D01*
G01X698418D01*
G02X698575Y357281I-1J-200D01*
G01X698798Y356995D01*
X698817Y356906D01*
X698805Y356860D01*
G03X698698Y356002I3395J-859D01*
G01Y356000D01*
G03X705702I3502J0D01*
G01Y356002D01*
G03X705595Y356860I-3502J-1D01*
G01X705583Y356906D01*
X705602Y356995D01*
X705825Y357281D01*
G02X705982Y357358I158J-123D01*
G01X707185D01*
X707219Y357345D01*
G03X708281I531J1405D01*
G01X708315Y357358D01*
X752097D01*
G02X752238Y357300I0J-200D01*
G01X752439Y357100D01*
G02X752498Y356968I-141J-142D01*
G01Y356957D01*
G03X754000Y355455I1502J0D01*
G03X755502Y356949I0J1502D01*
G01Y356959D01*
X755504Y356978D01*
G02X755557Y357096I199J-19D01*
G01X755559Y357099D01*
X755762Y357300D01*
G02X755903Y357358I141J-142D01*
G01X781202D01*
G02X781235Y357355I-2J-200D01*
G02X781342Y357301I-32J-197D01*
G01X784374Y354269D01*
G02X784433Y354127I-141J-142D01*
G01Y321828D01*
G03X784492Y321686I200J0D01*
G01X786596Y319582D01*
G03X786738Y319523I142J141D01*
G01X817700D01*
G02X817840Y319466I0J-200D01*
G01X817865Y319441D01*
X818083Y319131D01*
X818097Y319035D01*
X818081Y318990D01*
G03X817998Y318500I1419J-492D01*
G03X819500Y316998I1502J0D01*
G03X820012Y317088I0J1501D01*
G01X820045Y317100D01*
X830682D01*
G02X830744Y317090I0J-200D01*
G01X830835Y317059D01*
X830860Y317040D01*
G03X831750Y316748I890J1210D01*
G03X833252Y318250I0J1502D01*
G03X833084Y318938I-1502J-2D01*
G01X833060Y318986D01*
X833063Y319089D01*
X833269Y319427D01*
G02X833440Y319523I171J-104D01*
G01X837284D01*
G02X837319Y319520I0J-200D01*
G03X837575Y319498I256J1480D01*
G03X837815Y319517I2J1502D01*
G01X837847Y319523D01*
X861099D01*
G02X861132Y319520I-2J-200D01*
G02X861239Y319466I-32J-197D01*
G01X864641Y316064D01*
G02X864700Y315922I-141J-142D01*
G01Y314760D01*
X864623Y314656D01*
X864559Y314636D01*
G03Y311764I441J-1436D01*
G01X864560D01*
G02X864700Y311573I-60J-191D01*
G01Y279895D01*
G03X864759Y279753I200J0D01*
G01X864967Y279545D01*
G02X864997Y279301I-142J-141D01*
G03X864498Y277500I3003J-1802D01*
G03X866373Y274399I3502J0D01*
G01X866379Y274396D01*
G02X866444Y274338I-97J-174D01*
G01X866520Y274235D01*
X866529Y274192D01*
G03X867037Y273347I1470J309D01*
G01X867044Y273341D01*
X867060Y273325D01*
X867085Y273301D01*
X867154Y273157D01*
Y272911D01*
G02X867149Y272867I-200J0D01*
G01X867139Y272823D01*
G02X867124Y272781I-195J46D01*
G01X867085Y272699D01*
X867060Y272675D01*
X867044Y272659D01*
X867037Y272653D01*
G03X866498Y271500I964J-1153D01*
G03X869502I1502J0D01*
G03X868963Y272653I-1503J0D01*
G01X868956Y272659D01*
X868940Y272675D01*
X868915Y272699D01*
X868865Y272803D01*
G02X868846Y272889I181J85D01*
G01Y273112D01*
X868866Y273196D01*
X868875Y273216D01*
X868898Y273266D01*
G02X868938Y273323I181J-85D01*
G01X868956Y273341D01*
X868963Y273347D01*
G03X869471Y274192I-962J1154D01*
G01X869480Y274235D01*
X869556Y274338D01*
G02X869621Y274396I162J-116D01*
G01X869627Y274399D01*
G03X870369Y274921I-1627J3101D01*
G01X870396Y274946D01*
X870529Y275000D01*
X877917D01*
G02X877950Y274997I-2J-200D01*
G02X878057Y274943I-32J-197D01*
G01X880441Y272559D01*
G02X880500Y272417I-141J-142D01*
G01Y233928D01*
X880493Y233884D01*
X880490Y233873D01*
G03X879698Y228001I21396J-5875D01*
G03X901884Y205814I22187J0D01*
G01X1007803D01*
G02X1007943Y205757I0J-200D01*
G01X1011541Y202159D01*
G02X1011543Y202157I-140J-142D01*
G02X1011600Y202017I-143J-140D01*
G01Y145583D01*
G03X1011659Y145441I200J0D01*
G01X1033341Y123759D01*
G03X1033483Y123700I142J141D01*
G01X1060017D01*
G03X1060159Y123759I0J200D01*
G01X1066641Y130241D01*
G02X1066643Y130243I142J-140D01*
G02X1066783Y130300I140J-143D01*
G01X1073200D01*
X1078500Y125000D01*
X1104000D01*
X1115000Y114000D01*
X1133400D01*
X1153177Y133776D01*
G02X1153179Y133778I142J-140D01*
G02X1153319Y133835I140J-143D01*
G01X1190688D01*
G03X1190830Y133894I0J200D01*
G01X1192429Y135493D01*
G02X1192474Y135527I142J-141D01*
G01X1192496Y135539D01*
X1192523Y135546D01*
X1192524D01*
G03X1192618Y135599I-48J194D01*
G01X1199227Y142208D01*
G03X1199286Y142350I-141J142D01*
G01Y192583D01*
G02X1199345Y192725I200J0D01*
G01X1218340Y211720D01*
G03X1218399Y211862I-141J142D01*
G01Y271812D01*
G02X1218458Y271954I200J0D01*
G01X1223038Y276534D01*
G02X1223180Y276593I142J-141D01*
G01X1260770D01*
G03X1260912Y276652I0J200D01*
G01X1271301Y287041D01*
G03X1271360Y287183I-141J142D01*
G01Y482988D01*
G03X1271301Y483130I-200J0D01*
G01X1263490Y490941D01*
G03X1263348Y491000I-142J-141D01*
G01X1188893D01*
X1182188Y497705D01*
Y518880D01*
X1172862Y528206D01*
X1172559D01*
G03X1172417Y528265I-142J-141D01*
G01X1100773D01*
X1100699Y528295D01*
X1100671Y528324D01*
X1098440Y530555D01*
G02X1098381Y530697I141J142D01*
G01Y566836D01*
G02X1098440Y566978I200J0D01*
G01X1104515Y573053D01*
G02X1104657Y573112I142J-141D01*
G37*
G36*
G01X949059Y359941D02*
X951941Y357059D01*
G02X952000Y356917I-141J-142D01*
G01Y280583D01*
G02X951941Y280441I-200J0D01*
G01X950059Y278559D01*
G02X949917Y278500I-142J141D01*
G01X870083D01*
G02X869941Y278559I0J200D01*
G01X868059Y280441D01*
G02X868000Y280583I141J142D01*
G01Y287823D01*
X868074Y287926D01*
X868135Y287947D01*
G03Y294573I-1135J3313D01*
G01X868074Y294594D01*
X868000Y294697D01*
Y309229D01*
G02X868091Y309397I200J0D01*
G01X868416Y309607D01*
X868518Y309615D01*
X868564Y309594D01*
G03X870000Y309286I1436J3194D01*
G03Y316290I0J3502D01*
G03X868564Y315982I0J-3502D01*
G01X868518Y315961D01*
X868416Y315969D01*
X868091Y316179D01*
G02X868000Y316347I109J168D01*
G01Y318641D01*
G03X867941Y318783I-200J0D01*
G01X863186Y323538D01*
G03X863044Y323597I-142J-141D01*
G01X840000D01*
G02X839869Y323646I0J200D01*
G03X835281I-2294J-2645D01*
G02X835150Y323597I-131J151D01*
G01X802301D01*
G02X802161Y323654I0J200D01*
G01X801933Y323877D01*
X801902Y323948D01*
X801901Y323987D01*
G03X798400Y327402I-3501J-87D01*
G03X796213Y326635I0J-3501D01*
G02X795964Y326634I-125J156D01*
G03X793801Y327382I-2163J-2754D01*
G01X793800D01*
G03X790352Y324493I0J-3502D01*
G02X790215Y324337I-197J35D01*
G01X789877Y324230D01*
G02X789675Y324280I-60J191D01*
G01X788751Y325204D01*
G02X788692Y325346I141J142D01*
G01Y333659D01*
G02X788763Y333811I200J-1D01*
G03Y339157I-2263J2673D01*
G02X788692Y339309I129J153D01*
G01Y355398D01*
G02X788820Y355585I200J0D01*
G01X789169Y355719D01*
G02X789390Y355665I71J-187D01*
G03X792000Y354498I2610J2335D01*
G03X795502Y358000I0J3502D01*
G03X795194Y359436I-3502J0D01*
G01X795173Y359482D01*
X795181Y359584D01*
X795391Y359909D01*
G02X795559Y360000I168J-109D01*
G01X810997D01*
G02X811158Y359919I0J-200D01*
G03X811342Y359690I2820J2077D01*
G02X811392Y359558I-150J-132D01*
G01Y359441D01*
G02X811342Y359310I-200J1D01*
G03X810473Y357000I2634J-2309D01*
G03X817477I3502J0D01*
G03X816608Y359310I-3503J1D01*
G02X816558Y359441I150J132D01*
G01Y359558D01*
G02X816608Y359690I200J0D01*
G03X816792Y359919I-2636J2306D01*
G02X816953Y360000I161J-119D01*
G01X825498D01*
X825597Y359935D01*
X825621Y359879D01*
G03X828379I1379J596D01*
G01X828403Y359935D01*
X828502Y360000D01*
X846809D01*
G02X847008Y359815I0J-200D01*
G03X848895Y356962I3492J259D01*
G02X849003Y356801I-91J-178D01*
G03X851997I1497J124D01*
G02X852105Y356962I199J-17D01*
G03X853992Y359815I-1605J3112D01*
G01X853998Y359894D01*
X854112Y360000D01*
X860756D01*
G02X860916Y359920I0J-200D01*
G01X861108Y359663D01*
G02X861140Y359487I-160J-120D01*
G03X860998Y358500I3359J-987D01*
G03X864500Y354998I3502J0D01*
G03X867690Y357056I0J3501D01*
G02X867933Y357164I182J-83D01*
G03X868997Y356998I1065J3336D01*
G01X869000D01*
G03X872439Y359838I0J3502D01*
G01X872453Y359909D01*
X872563Y360000D01*
X874264D01*
G02X874424Y359919I-1J-200D01*
G01X874644Y359624D01*
X874661Y359530D01*
X874647Y359485D01*
G03X874498Y358475I3353J-1011D01*
G03X878000Y354973I3502J0D01*
G03X880323Y355854I0J3503D01*
G02X880455Y355904I132J-150D01*
G01X880572Y355905D01*
G02X880704Y355856I1J-200D01*
G03X883000Y354998I2297J2645D01*
G03X886502Y358500I0J3502D01*
G03X886360Y359487I-3501J0D01*
G01X886347Y359533D01*
X886363Y359625D01*
X886584Y359920D01*
G02X886744Y360000I160J-120D01*
G01X907516D01*
G02X907704Y359869I0J-200D01*
G03X914280I3288J1206D01*
G02X914468Y360000I188J-69D01*
G01X923524D01*
G02X923712Y359869I0J-200D01*
G03X925395Y357962I3288J1206D01*
G02X925503Y357801I-91J-178D01*
G03X928497I1497J124D01*
G02X928605Y357962I199J-17D01*
G03X930288Y359869I-1605J3113D01*
G02X930476Y360000I188J-69D01*
G01X932040D01*
G02X932228Y359869I0J-200D01*
G03X938804I3288J1206D01*
G02X938992Y360000I188J-69D01*
G01X948917D01*
G02X949059Y359941I0J-200D01*
G37*
G36*
G01X1157783Y186500D02*
X1171917D01*
G02X1172059Y186441I0J-200D01*
G01X1172941Y185559D01*
G02X1173000Y185417I-141J-142D01*
G01Y178083D01*
G02X1172941Y177941I-200J0D01*
G01X1150559Y155559D01*
G03X1150500Y155417I141J-142D01*
G01Y151615D01*
G03X1150498Y151500I3500J-118D01*
G03X1150500Y151385I3502J3D01*
G01Y149083D01*
G02X1150441Y148941I-200J0D01*
G01X1137809Y136309D01*
G03X1137750Y136167I141J-142D01*
G01Y132833D01*
G02X1137691Y132691I-200J0D01*
G01X1130559Y125559D01*
G02X1130417Y125500I-142J141D01*
G01X1127083D01*
G03X1126941Y125441I0J-200D01*
G01X1123718Y122218D01*
X1123602Y122194D01*
X1123546Y122215D01*
G03X1123000Y122318I-547J-1399D01*
G03X1122126Y122037I1J-1502D01*
G02X1122009Y122000I-116J163D01*
G01X1113483D01*
G02X1113341Y122059I0J200D01*
G01X1106459Y128941D01*
G03X1106317Y129000I-142J-141D01*
G01X1080983D01*
G02X1080841Y129059I0J200D01*
G01X1079990Y129910D01*
G02X1079931Y130052I141J142D01*
G01Y133042D01*
G02X1079990Y133184I200J0D01*
G01X1082441Y135635D01*
G02X1082583Y135694I142J-141D01*
G01X1097223D01*
G02X1097365Y135635I0J-200D01*
G01X1099941Y133059D01*
G03X1100083Y133000I142J141D01*
G01X1108385D01*
G03X1108500Y132998I118J3500D01*
G03X1108615Y133000I-3J3502D01*
G01X1112417D01*
G02X1112559Y132941I0J-200D01*
G01X1112941Y132559D01*
G03X1113083Y132500I142J141D01*
G01X1125625D01*
X1125638Y132498D01*
G03X1126075Y132471I434J3475D01*
G03X1126512Y132498I3J3502D01*
G01X1126525Y132500D01*
X1129469D01*
X1129487Y132497D01*
G03X1130125Y132438I640J3443D01*
G03X1130763Y132497I-2J3502D01*
G01X1130781Y132500D01*
X1131917D01*
G03X1132059Y132559I0J200D01*
G01X1133691Y134191D01*
G03X1133750Y134333I-141J142D01*
G01Y147667D01*
G02X1133809Y147809I200J0D01*
G01X1143941Y157941D01*
G03X1144000Y158083I-141J142D01*
G01Y172717D01*
G02X1144059Y172859I200J0D01*
G01X1157641Y186441D01*
G02X1157783Y186500I142J-141D01*
G37*
G36*
G01X1101287Y377500D02*
X1163400D01*
X1165300Y375600D01*
Y330396D01*
G03X1165070Y330412I-230J-1645D01*
G03Y327088I0J-1662D01*
G03X1165300Y327104I0J1661D01*
G01Y243200D01*
X1163900Y241800D01*
X1101120D01*
X1098420Y244500D01*
Y374633D01*
X1101287Y377500D01*
G37*
G36*
G01X1163250Y382000D02*
X1100000D01*
X1098420Y383580D01*
Y517133D01*
X1101287Y520000D01*
X1161300D01*
X1162950Y518350D01*
Y465350D01*
X1165350Y462950D01*
Y384100D01*
X1163250Y382000D01*
G37*
G36*
G01X1199110Y479104D02*
X1257495D01*
G02X1257637Y479045I0J-200D01*
G01X1261472Y475209D01*
G02X1261531Y475067I-141J-142D01*
G01Y303534D01*
G02X1261472Y303392I-200J0D01*
G01X1258632Y300552D01*
G02X1258490Y300493I-142J141D01*
G01X1214416D01*
G03X1214274Y300434I0J-200D01*
G01X1205399Y291559D01*
G02X1205257Y291500I-142J141D01*
G01X1198083D01*
G02X1197941Y291559I0J200D01*
G01X1196302Y293198D01*
G02X1196243Y293340I141J142D01*
G01Y476237D01*
G02X1196302Y476379I200J0D01*
G01X1198968Y479045D01*
G02X1199110Y479104I142J-141D01*
G37*
%LPC*%
G75*
G36*
G01X36402Y235743D02*
Y236146D01*
X36363Y236227D01*
X36328Y236256D01*
G02X34878Y239291I2451J3035D01*
G02X42682I3902J0D01*
G02X41232Y236256I-3901J0D01*
G01X41197Y236227D01*
X41158Y236146D01*
Y235743D01*
X41197Y235662D01*
X41232Y235633D01*
G02X42682Y232598I-2451J-3035D01*
G02X34878I-3902J0D01*
G02X36328Y235633I3901J0D01*
G01X36363Y235662D01*
X36402Y235743D01*
G37*
G36*
G01X46402D02*
Y236146D01*
X46363Y236227D01*
X46328Y236256D01*
G02X44878Y239291I2451J3035D01*
G02X52682I3902J0D01*
G02X51232Y236256I-3901J0D01*
G01X51197Y236227D01*
X51158Y236146D01*
Y235743D01*
X51197Y235662D01*
X51232Y235633D01*
G02X52682Y232598I-2451J-3035D01*
G02X44878I-3902J0D01*
G02X46328Y235633I3901J0D01*
G01X46363Y235662D01*
X46402Y235743D01*
G37*
G36*
G01X36402Y255743D02*
Y256146D01*
X36363Y256227D01*
X36328Y256256D01*
G02X34878Y259291I2451J3035D01*
G02X42682I3902J0D01*
G02X41232Y256256I-3901J0D01*
G01X41197Y256227D01*
X41158Y256146D01*
Y255743D01*
X41197Y255662D01*
X41232Y255633D01*
G02X42682Y252598I-2451J-3035D01*
G02X34878I-3902J0D01*
G02X36328Y255633I3901J0D01*
G01X36363Y255662D01*
X36402Y255743D01*
G37*
G36*
G01X46402D02*
Y256146D01*
X46363Y256227D01*
X46328Y256256D01*
G02X44878Y259291I2451J3035D01*
G02X52682I3902J0D01*
G02X51232Y256256I-3901J0D01*
G01X51197Y256227D01*
X51158Y256146D01*
Y255743D01*
X51197Y255662D01*
X51232Y255633D01*
G02X52682Y252598I-2451J-3035D01*
G02X44878I-3902J0D01*
G02X46328Y255633I3901J0D01*
G01X46363Y255662D01*
X46402Y255743D01*
G37*
G36*
G01X36402Y275743D02*
Y276146D01*
X36363Y276227D01*
X36328Y276256D01*
G02X34878Y279291I2451J3035D01*
G02X42682I3902J0D01*
G02X41232Y276256I-3901J0D01*
G01X41197Y276227D01*
X41158Y276146D01*
Y275743D01*
X41197Y275662D01*
X41232Y275633D01*
G02X42682Y272598I-2451J-3035D01*
G02X34878I-3902J0D01*
G02X36328Y275633I3901J0D01*
G01X36363Y275662D01*
X36402Y275743D01*
G37*
G36*
G01X46402D02*
Y276146D01*
X46363Y276227D01*
X46328Y276256D01*
G02X44878Y279291I2451J3035D01*
G02X52682I3902J0D01*
G02X51232Y276256I-3901J0D01*
G01X51197Y276227D01*
X51158Y276146D01*
Y275743D01*
X51197Y275662D01*
X51232Y275633D01*
G02X52682Y272598I-2451J-3035D01*
G02X44878I-3902J0D01*
G02X46328Y275633I3901J0D01*
G01X46363Y275662D01*
X46402Y275743D01*
G37*
G36*
G01X36402Y295743D02*
Y296146D01*
X36363Y296227D01*
X36328Y296256D01*
G02X34878Y299291I2451J3035D01*
G02X42682I3902J0D01*
G02X41232Y296256I-3901J0D01*
G01X41197Y296227D01*
X41158Y296146D01*
Y295743D01*
X41197Y295662D01*
X41232Y295633D01*
G02X42682Y292598I-2451J-3035D01*
G02X34878I-3902J0D01*
G02X36328Y295633I3901J0D01*
G01X36363Y295662D01*
X36402Y295743D01*
G37*
G36*
G01X46402D02*
Y296146D01*
X46363Y296227D01*
X46328Y296256D01*
G02X44878Y299291I2451J3035D01*
G02X52682I3902J0D01*
G02X51232Y296256I-3901J0D01*
G01X51197Y296227D01*
X51158Y296146D01*
Y295743D01*
X51197Y295662D01*
X51232Y295633D01*
G02X52682Y292598I-2451J-3035D01*
G02X44878I-3902J0D01*
G02X46328Y295633I3901J0D01*
G01X46363Y295662D01*
X46402Y295743D01*
G37*
G36*
G01X239719Y245128D02*
G03Y245372I-159J122D01*
G02X238998Y247500I2780J2128D01*
G02X246002I3502J0D01*
G02X245281Y245372I-3501J0D01*
G03Y245128I159J-122D01*
G02X246002Y243000I-2780J-2128D01*
G02X245958Y242450I-3502J3D01*
G01Y242449D01*
X245952Y242408D01*
X245962Y242369D01*
G03X245998Y242295I194J49D01*
G01X246203Y242031D01*
X246275Y241992D01*
X246317Y241988D01*
G02X249502Y238500I-317J-3488D01*
G01Y238498D01*
G02X249202Y237081I-3502J1D01*
G03Y236919I183J-81D01*
G02X249502Y235502I-3202J-1418D01*
G01Y235500D01*
G02X242498I-3502J0D01*
G01Y235502D01*
G02X242798Y236919I3502J-1D01*
G03Y237081I-183J81D01*
G02X242498Y238498I3202J1418D01*
G01Y238500D01*
G02X242542Y239050I3502J-3D01*
G01Y239051D01*
X242548Y239092D01*
X242538Y239131D01*
G03X242502Y239205I-194J-49D01*
G01X242297Y239469D01*
X242225Y239508D01*
X242183Y239512D01*
G02X238998Y243000I317J3488D01*
G02X239719Y245128I3501J0D01*
G37*
G36*
G01X706218Y245778D02*
G02X705998Y246999I3282J1222D01*
G01Y247000D01*
G02X713002I3502J0D01*
G02X712577Y245328I-3501J0D01*
G03X712576Y245139I176J-95D01*
G02X712983Y243501I-3095J-1639D01*
G01Y243500D01*
G02X712939Y242950I-3502J3D01*
G01Y242949D01*
X712933Y242908D01*
X712943Y242869D01*
G03X712979Y242795I194J49D01*
G01X713184Y242531D01*
X713256Y242492D01*
X713298Y242488D01*
G02X716483Y239000I-317J-3488D01*
G01Y238998D01*
G02X716183Y237581I-3502J1D01*
G03Y237419I183J-81D01*
G02X716483Y236002I-3202J-1418D01*
G01Y236000D01*
G02X709479I-3502J0D01*
G01Y236002D01*
G02X709779Y237419I3502J-1D01*
G03Y237581I-183J81D01*
G02X709479Y238998I3202J1418D01*
G01Y239000D01*
G02X709523Y239550I3502J-3D01*
G01Y239551D01*
X709529Y239592D01*
X709519Y239631D01*
G03X709483Y239705I-194J-49D01*
G01X709278Y239969D01*
X709206Y240008D01*
X709164Y240012D01*
G02X705979Y243500I317J3488D01*
G02X706404Y245172I3501J0D01*
G03X706405Y245361I-176J95D01*
G02X706236Y245731I3096J1638D01*
G01X706218Y245778D01*
G37*
G36*
G01X548914Y245155D02*
G03Y245345I-176J95D01*
G02X548498Y247000I3086J1655D01*
G02X555502I3502J0D01*
G02X555086Y245345I-3502J0D01*
G03Y245155I176J-95D01*
G02X555502Y243500I-3086J-1655D01*
G02X555458Y242950I-3502J3D01*
G01Y242949D01*
X555452Y242908D01*
X555462Y242869D01*
G03X555498Y242795I194J49D01*
G01X555703Y242531D01*
X555775Y242492D01*
X555817Y242488D01*
G02X559002Y239000I-317J-3488D01*
G01Y238998D01*
G02X558702Y237581I-3502J1D01*
G03Y237419I183J-81D01*
G02X559002Y236002I-3202J-1418D01*
G01Y236000D01*
G02X551998I-3502J0D01*
G01Y236002D01*
G02X552298Y237419I3502J-1D01*
G03Y237581I-183J81D01*
G02X551998Y238998I3202J1418D01*
G01Y239000D01*
G02X552042Y239550I3502J-3D01*
G01Y239551D01*
X552048Y239592D01*
X552038Y239631D01*
G03X552002Y239705I-194J-49D01*
G01X551797Y239969D01*
X551725Y240008D01*
X551683Y240012D01*
G02X548498Y243500I317J3488D01*
G02X548914Y245155I3502J0D01*
G37*
G36*
G01X395719Y244628D02*
G03Y244872I-159J122D01*
G02X394998Y247000I2780J2128D01*
G02X402002I3502J0D01*
G02X401281Y244872I-3501J0D01*
G03Y244628I159J-122D01*
G02X402002Y242500I-2780J-2128D01*
G02X401958Y241950I-3502J3D01*
G01Y241949D01*
X401952Y241908D01*
X401962Y241869D01*
G03X401998Y241795I194J49D01*
G01X402203Y241531D01*
X402275Y241492D01*
X402317Y241488D01*
G02X405502Y238000I-317J-3488D01*
G01Y237998D01*
G02X405202Y236581I-3502J1D01*
G03Y236419I183J-81D01*
G02X405502Y235002I-3202J-1418D01*
G01Y235000D01*
G02X398498I-3502J0D01*
G01Y235002D01*
G02X398798Y236419I3502J-1D01*
G03Y236581I-183J81D01*
G02X398498Y237998I3202J1418D01*
G01Y238000D01*
G02X398542Y238550I3502J-3D01*
G01Y238551D01*
X398548Y238592D01*
X398538Y238631D01*
G03X398502Y238705I-194J-49D01*
G01X398297Y238969D01*
X398225Y239008D01*
X398183Y239012D01*
G02X394998Y242500I317J3488D01*
G02X395719Y244628I3501J0D01*
G37*
G36*
G01X195761Y248602D02*
G02X197179Y248302I0J-3502D01*
G03X197341I81J183D01*
G02X198759Y248602I1418J-3202D01*
G01X198760D01*
X198761D01*
G02X200179Y248302I0J-3502D01*
G03X200341I81J183D01*
G02X201758Y248602I1418J-3202D01*
G01X201760D01*
G02X205262Y245100I0J-3502D01*
G01Y245098D01*
G02X204962Y243681I-3502J1D01*
G03Y243519I183J-81D01*
G02X205262Y242102I-3202J-1418D01*
G01Y242100D01*
G02X201760Y238598I-3502J0D01*
G01X201758D01*
G02X200341Y238898I1J3502D01*
G03X200179I-81J-183D01*
G02X198761Y238598I-1418J3202D01*
G01X198760D01*
X198759D01*
G02X197341Y238898I0J3502D01*
G03X197179I-81J-183D01*
G02X195761Y238598I-1418J3202D01*
G01X195760D01*
X195759D01*
G02X194341Y238898I0J3502D01*
G03X194179I-81J-183D01*
G02X192761Y238598I-1418J3202D01*
G01X192760D01*
X192759D01*
G02X191341Y238898I0J3502D01*
G03X191179I-81J-183D01*
G02X189762Y238598I-1418J3202D01*
G01X189760D01*
G02X186258Y242100I0J3502D01*
G01Y242102D01*
G02X186558Y243519I3502J-1D01*
G03Y243681I-183J81D01*
G02X186258Y245098I3202J1418D01*
G01Y245100D01*
G02X189760Y248602I3502J0D01*
G01X189762D01*
G02X191179Y248302I-1J-3502D01*
G03X191341I81J183D01*
G02X192759Y248602I1418J-3202D01*
G01X192760D01*
X192761D01*
G02X194179Y248302I0J-3502D01*
G03X194341I81J183D01*
G02X195759Y248602I1418J-3202D01*
G01X195760D01*
X195761D01*
G37*
G36*
G01X422704Y204682D02*
G03Y204818I-189J68D01*
G02X422498Y206000I3296J1183D01*
G02X426000Y209502I3502J0D01*
G02X429502Y206000I0J-3502D01*
G02X429296Y204818I-3502J1D01*
G03Y204682I189J-68D01*
G02X429502Y203500I-3296J-1183D01*
G02X428633Y201191I-3502J0D01*
G01X428608Y201163D01*
X428583Y201096D01*
Y200904D01*
X428608Y200837D01*
X428633Y200809D01*
G02X429502Y198500I-2633J-2309D01*
G02X429296Y197318I-3502J1D01*
G03Y197182I189J-68D01*
G02X429502Y196000I-3296J-1183D01*
G02X426000Y192498I-3502J0D01*
G02X422498Y196000I0J3502D01*
G02X422704Y197182I3502J-1D01*
G03Y197318I-189J68D01*
G02X422498Y198500I3296J1183D01*
G02X423367Y200809I3502J0D01*
G01X423392Y200837D01*
X423417Y200904D01*
Y201096D01*
X423392Y201163D01*
X423367Y201191D01*
G02X422498Y203500I2633J2309D01*
G02X422704Y204682I3502J-1D01*
G37*
G36*
G01X401204D02*
G03Y204818I-189J68D01*
G02X400998Y206000I3296J1183D01*
G02X404500Y209502I3502J0D01*
G02X408002Y206000I0J-3502D01*
G02X407796Y204818I-3502J1D01*
G03Y204682I189J-68D01*
G02X408002Y203500I-3296J-1183D01*
G02X407133Y201191I-3502J0D01*
G01X407108Y201163D01*
X407083Y201096D01*
Y200904D01*
X407108Y200837D01*
X407133Y200809D01*
G02X408002Y198500I-2633J-2309D01*
G02X407796Y197318I-3502J1D01*
G03Y197182I189J-68D01*
G02X408002Y196000I-3296J-1183D01*
G02X404500Y192498I-3502J0D01*
G02X400998Y196000I0J3502D01*
G02X401204Y197182I3502J-1D01*
G03Y197318I-189J68D01*
G02X400998Y198500I3296J1183D01*
G02X401867Y200809I3502J0D01*
G01X401892Y200837D01*
X401917Y200904D01*
Y201096D01*
X401892Y201163D01*
X401867Y201191D01*
G02X400998Y203500I2633J2309D01*
G02X401204Y204682I3502J-1D01*
G37*
G36*
G01X379704D02*
G03Y204818I-189J68D01*
G02X379498Y206000I3296J1183D01*
G02X383000Y209502I3502J0D01*
G02X386502Y206000I0J-3502D01*
G02X386296Y204818I-3502J1D01*
G03Y204682I189J-68D01*
G02X386502Y203500I-3296J-1183D01*
G02X385633Y201191I-3502J0D01*
G01X385608Y201163D01*
X385583Y201096D01*
Y200904D01*
X385608Y200837D01*
X385633Y200809D01*
G02X386502Y198500I-2633J-2309D01*
G02X386296Y197318I-3502J1D01*
G03Y197182I189J-68D01*
G02X386502Y196000I-3296J-1183D01*
G02X383000Y192498I-3502J0D01*
G02X379498Y196000I0J3502D01*
G02X379704Y197182I3502J-1D01*
G03Y197318I-189J68D01*
G02X379498Y198500I3296J1183D01*
G02X380367Y200809I3502J0D01*
G01X380392Y200837D01*
X380417Y200904D01*
Y201096D01*
X380392Y201163D01*
X380367Y201191D01*
G02X379498Y203500I2633J2309D01*
G02X379704Y204682I3502J-1D01*
G37*
G36*
G01X358204D02*
G03Y204818I-189J68D01*
G02X357998Y206000I3296J1183D01*
G02X361500Y209502I3502J0D01*
G02X365002Y206000I0J-3502D01*
G02X364796Y204818I-3502J1D01*
G03Y204682I189J-68D01*
G02X365002Y203500I-3296J-1183D01*
G02X364133Y201191I-3502J0D01*
G01X364108Y201163D01*
X364083Y201096D01*
Y200904D01*
X364108Y200837D01*
X364133Y200809D01*
G02X365002Y198500I-2633J-2309D01*
G02X364796Y197318I-3502J1D01*
G03Y197182I189J-68D01*
G02X365002Y196000I-3296J-1183D01*
G02X361500Y192498I-3502J0D01*
G02X357998Y196000I0J3502D01*
G02X358204Y197182I3502J-1D01*
G03Y197318I-189J68D01*
G02X357998Y198500I3296J1183D01*
G02X358867Y200809I3502J0D01*
G01X358892Y200837D01*
X358917Y200904D01*
Y201096D01*
X358892Y201163D01*
X358867Y201191D01*
G02X357998Y203500I2633J2309D01*
G02X358204Y204682I3502J-1D01*
G37*
G36*
G01X336704D02*
G03Y204818I-189J68D01*
G02X336498Y206000I3296J1183D01*
G02X340000Y209502I3502J0D01*
G02X343502Y206000I0J-3502D01*
G02X343296Y204818I-3502J1D01*
G03Y204682I189J-68D01*
G02X343502Y203500I-3296J-1183D01*
G02X342633Y201191I-3502J0D01*
G01X342608Y201163D01*
X342583Y201096D01*
Y200904D01*
X342608Y200837D01*
X342633Y200809D01*
G02X343502Y198500I-2633J-2309D01*
G02X343296Y197318I-3502J1D01*
G03Y197182I189J-68D01*
G02X343502Y196000I-3296J-1183D01*
G02X340000Y192498I-3502J0D01*
G02X336498Y196000I0J3502D01*
G02X336704Y197182I3502J-1D01*
G03Y197318I-189J68D01*
G02X336498Y198500I3296J1183D01*
G02X337367Y200809I3502J0D01*
G01X337392Y200837D01*
X337417Y200904D01*
Y201096D01*
X337392Y201163D01*
X337367Y201191D01*
G02X336498Y203500I2633J2309D01*
G02X336704Y204682I3502J-1D01*
G37*
G36*
G01X315204D02*
G03Y204818I-189J68D01*
G02X314998Y206000I3296J1183D01*
G02X318500Y209502I3502J0D01*
G02X322002Y206000I0J-3502D01*
G02X321796Y204818I-3502J1D01*
G03Y204682I189J-68D01*
G02X322002Y203500I-3296J-1183D01*
G02X321133Y201191I-3502J0D01*
G01X321108Y201163D01*
X321083Y201096D01*
Y200904D01*
X321108Y200837D01*
X321133Y200809D01*
G02X322002Y198500I-2633J-2309D01*
G02X321796Y197318I-3502J1D01*
G03Y197182I189J-68D01*
G02X322002Y196000I-3296J-1183D01*
G02X318500Y192498I-3502J0D01*
G02X314998Y196000I0J3502D01*
G02X315204Y197182I3502J-1D01*
G03Y197318I-189J68D01*
G02X314998Y198500I3296J1183D01*
G02X315867Y200809I3502J0D01*
G01X315892Y200837D01*
X315917Y200904D01*
Y201096D01*
X315892Y201163D01*
X315867Y201191D01*
G02X314998Y203500I2633J2309D01*
G02X315204Y204682I3502J-1D01*
G37*
G36*
G01X293704D02*
G03Y204818I-189J68D01*
G02X293498Y206000I3296J1183D01*
G02X297000Y209502I3502J0D01*
G02X300502Y206000I0J-3502D01*
G02X300296Y204818I-3502J1D01*
G03Y204682I189J-68D01*
G02X300502Y203500I-3296J-1183D01*
G02X299633Y201191I-3502J0D01*
G01X299608Y201163D01*
X299583Y201096D01*
Y200904D01*
X299608Y200837D01*
X299633Y200809D01*
G02X300502Y198500I-2633J-2309D01*
G02X300296Y197318I-3502J1D01*
G03Y197182I189J-68D01*
G02X300502Y196000I-3296J-1183D01*
G02X297000Y192498I-3502J0D01*
G02X293498Y196000I0J3502D01*
G02X293704Y197182I3502J-1D01*
G03Y197318I-189J68D01*
G02X293498Y198500I3296J1183D01*
G02X294367Y200809I3502J0D01*
G01X294392Y200837D01*
X294417Y200904D01*
Y201096D01*
X294392Y201163D01*
X294367Y201191D01*
G02X293498Y203500I2633J2309D01*
G02X293704Y204682I3502J-1D01*
G37*
G36*
G01X730194Y204182D02*
G03Y204318I-189J68D01*
G02X729988Y205500I3296J1183D01*
G02X736992I3502J0D01*
G02X736786Y204318I-3502J1D01*
G03Y204182I189J-68D01*
G02X736992Y203000I-3296J-1183D01*
G02X736123Y200691I-3502J0D01*
G01X736098Y200663D01*
X736073Y200596D01*
Y200404D01*
X736098Y200337D01*
X736123Y200309D01*
G02X736992Y198000I-2633J-2309D01*
G02X736786Y196818I-3502J1D01*
G03Y196682I189J-68D01*
G02X736992Y195500I-3296J-1183D01*
G02X729988I-3502J0D01*
G02X730194Y196682I3502J-1D01*
G03Y196818I-189J68D01*
G02X729988Y198000I3296J1183D01*
G02X730857Y200309I3502J0D01*
G01X730882Y200337D01*
X730907Y200404D01*
Y200596D01*
X730882Y200663D01*
X730857Y200691D01*
G02X729988Y203000I2633J2309D01*
G02X730194Y204182I3502J-1D01*
G37*
G36*
G01X708694D02*
G03Y204318I-189J68D01*
G02X708488Y205500I3296J1183D01*
G02X715492I3502J0D01*
G02X715286Y204318I-3502J1D01*
G03Y204182I189J-68D01*
G02X715492Y203000I-3296J-1183D01*
G02X714623Y200691I-3502J0D01*
G01X714598Y200663D01*
X714573Y200596D01*
Y200404D01*
X714598Y200337D01*
X714623Y200309D01*
G02X715492Y198000I-2633J-2309D01*
G02X715286Y196818I-3502J1D01*
G03Y196682I189J-68D01*
G02X715492Y195500I-3296J-1183D01*
G02X708488I-3502J0D01*
G02X708694Y196682I3502J-1D01*
G03Y196818I-189J68D01*
G02X708488Y198000I3296J1183D01*
G02X709357Y200309I3502J0D01*
G01X709382Y200337D01*
X709407Y200404D01*
Y200596D01*
X709382Y200663D01*
X709357Y200691D01*
G02X708488Y203000I2633J2309D01*
G02X708694Y204182I3502J-1D01*
G37*
G36*
G01X687204D02*
G03Y204318I-189J68D01*
G02X686998Y205500I3296J1183D01*
G02X694002I3502J0D01*
G02X693796Y204318I-3502J1D01*
G03Y204182I189J-68D01*
G02X694002Y203000I-3296J-1183D01*
G02X693133Y200691I-3502J0D01*
G01X693108Y200663D01*
X693083Y200596D01*
Y200404D01*
X693108Y200337D01*
X693133Y200309D01*
G02X694002Y198000I-2633J-2309D01*
G02X693796Y196818I-3502J1D01*
G03Y196682I189J-68D01*
G02X694002Y195500I-3296J-1183D01*
G02X686998I-3502J0D01*
G02X687204Y196682I3502J-1D01*
G03Y196818I-189J68D01*
G02X686998Y198000I3296J1183D01*
G02X687867Y200309I3502J0D01*
G01X687892Y200337D01*
X687917Y200404D01*
Y200596D01*
X687892Y200663D01*
X687867Y200691D01*
G02X686998Y203000I2633J2309D01*
G02X687204Y204182I3502J-1D01*
G37*
G36*
G01X665704D02*
G03Y204318I-189J68D01*
G02X665498Y205500I3296J1183D01*
G02X672502I3502J0D01*
G02X672296Y204318I-3502J1D01*
G03Y204182I189J-68D01*
G02X672502Y203000I-3296J-1183D01*
G02X671633Y200691I-3502J0D01*
G01X671608Y200663D01*
X671583Y200596D01*
Y200404D01*
X671608Y200337D01*
X671633Y200309D01*
G02X672502Y198000I-2633J-2309D01*
G02X672296Y196818I-3502J1D01*
G03Y196682I189J-68D01*
G02X672502Y195500I-3296J-1183D01*
G02X665498I-3502J0D01*
G02X665704Y196682I3502J-1D01*
G03Y196818I-189J68D01*
G02X665498Y198000I3296J1183D01*
G02X666367Y200309I3502J0D01*
G01X666392Y200337D01*
X666417Y200404D01*
Y200596D01*
X666392Y200663D01*
X666367Y200691D01*
G02X665498Y203000I2633J2309D01*
G02X665704Y204182I3502J-1D01*
G37*
G36*
G01X644204D02*
G03Y204318I-189J68D01*
G02X643998Y205500I3296J1183D01*
G02X651002I3502J0D01*
G02X650796Y204318I-3502J1D01*
G03Y204182I189J-68D01*
G02X651002Y203000I-3296J-1183D01*
G02X650133Y200691I-3502J0D01*
G01X650108Y200663D01*
X650083Y200596D01*
Y200404D01*
X650108Y200337D01*
X650133Y200309D01*
G02X651002Y198000I-2633J-2309D01*
G02X650796Y196818I-3502J1D01*
G03Y196682I189J-68D01*
G02X651002Y195500I-3296J-1183D01*
G02X643998I-3502J0D01*
G02X644204Y196682I3502J-1D01*
G03Y196818I-189J68D01*
G02X643998Y198000I3296J1183D01*
G02X644867Y200309I3502J0D01*
G01X644892Y200337D01*
X644917Y200404D01*
Y200596D01*
X644892Y200663D01*
X644867Y200691D01*
G02X643998Y203000I2633J2309D01*
G02X644204Y204182I3502J-1D01*
G37*
G36*
G01X622704D02*
G03Y204318I-189J68D01*
G02X622498Y205500I3296J1183D01*
G02X626000Y209002I3502J0D01*
G02X629502Y205500I0J-3502D01*
G02X629296Y204318I-3502J1D01*
G03Y204182I189J-68D01*
G02X629502Y203000I-3296J-1183D01*
G02X628633Y200691I-3502J0D01*
G01X628608Y200663D01*
X628583Y200596D01*
Y200404D01*
X628608Y200337D01*
X628633Y200309D01*
G02X629502Y198000I-2633J-2309D01*
G02X629296Y196818I-3502J1D01*
G03Y196682I189J-68D01*
G02X629502Y195500I-3296J-1183D01*
G02X626000Y191998I-3502J0D01*
G02X622498Y195500I0J3502D01*
G02X622704Y196682I3502J-1D01*
G03Y196818I-189J68D01*
G02X622498Y198000I3296J1183D01*
G02X623367Y200309I3502J0D01*
G01X623392Y200337D01*
X623417Y200404D01*
Y200596D01*
X623392Y200663D01*
X623367Y200691D01*
G02X622498Y203000I2633J2309D01*
G02X622704Y204182I3502J-1D01*
G37*
G36*
G01X601204D02*
G03Y204318I-189J68D01*
G02X600998Y205500I3296J1183D01*
G02X604500Y209002I3502J0D01*
G02X608002Y205500I0J-3502D01*
G02X607796Y204318I-3502J1D01*
G03Y204182I189J-68D01*
G02X608002Y203000I-3296J-1183D01*
G02X607133Y200691I-3502J0D01*
G01X607108Y200663D01*
X607083Y200596D01*
Y200404D01*
X607108Y200337D01*
X607133Y200309D01*
G02X608002Y198000I-2633J-2309D01*
G02X607796Y196818I-3502J1D01*
G03Y196682I189J-68D01*
G02X608002Y195500I-3296J-1183D01*
G02X604500Y191998I-3502J0D01*
G02X600998Y195500I0J3502D01*
G02X601204Y196682I3502J-1D01*
G03Y196818I-189J68D01*
G02X600998Y198000I3296J1183D01*
G02X601867Y200309I3502J0D01*
G01X601892Y200337D01*
X601917Y200404D01*
Y200596D01*
X601892Y200663D01*
X601867Y200691D01*
G02X600998Y203000I2633J2309D01*
G02X601204Y204182I3502J-1D01*
G37*
G36*
G01X372090Y162620D02*
G02X376752Y165194I4662J-2935D01*
G02X382261Y159685I0J-5509D01*
G02X379687Y155023I-5509J0D01*
G01X379643Y154995D01*
X379594Y154906D01*
Y154464D01*
X379643Y154375D01*
X379687Y154347D01*
G02Y145023I-2936J-4662D01*
G01X379643Y144995D01*
X379594Y144906D01*
Y144464D01*
X379643Y144375D01*
X379687Y144347D01*
G02Y135023I-2936J-4662D01*
G01X379643Y134995D01*
X379594Y134906D01*
Y134464D01*
X379643Y134375D01*
X379687Y134347D01*
G02X382261Y129685I-2935J-4662D01*
G02X376752Y124176I-5509J0D01*
G02X372090Y126750I0J5509D01*
G01X372062Y126794D01*
X371973Y126843D01*
X371531D01*
X371442Y126794D01*
X371414Y126750D01*
G02X366752Y124176I-4662J2935D01*
G02X361243Y129685I0J5509D01*
G02X363817Y134347I5509J0D01*
G01X363861Y134375D01*
X363910Y134464D01*
Y134906D01*
X363861Y134995D01*
X363817Y135023D01*
G02Y144347I2936J4662D01*
G01X363861Y144375D01*
X363910Y144464D01*
Y144906D01*
X363861Y144995D01*
X363817Y145023D01*
G02Y154347I2936J4662D01*
G01X363861Y154375D01*
X363910Y154464D01*
Y154906D01*
X363861Y154995D01*
X363817Y155023D01*
G02X361243Y159685I2935J4662D01*
G02X366752Y165194I5509J0D01*
G02X371414Y162620I0J-5509D01*
G01X371442Y162576D01*
X371531Y162527D01*
X371973D01*
X372062Y162576D01*
X372090Y162620D01*
G37*
G36*
G01X337090D02*
G02X341752Y165194I4662J-2935D01*
G02X347261Y159685I0J-5509D01*
G02X344687Y155023I-5509J0D01*
G01X344643Y154995D01*
X344594Y154906D01*
Y154464D01*
X344643Y154375D01*
X344687Y154347D01*
G02Y145023I-2936J-4662D01*
G01X344643Y144995D01*
X344594Y144906D01*
Y144464D01*
X344643Y144375D01*
X344687Y144347D01*
G02Y135023I-2936J-4662D01*
G01X344643Y134995D01*
X344594Y134906D01*
Y134464D01*
X344643Y134375D01*
X344687Y134347D01*
G02X347261Y129685I-2935J-4662D01*
G02X341752Y124176I-5509J0D01*
G02X337090Y126750I0J5509D01*
G01X337062Y126794D01*
X336973Y126843D01*
X336531D01*
X336442Y126794D01*
X336414Y126750D01*
G02X331752Y124176I-4662J2935D01*
G02X326243Y129685I0J5509D01*
G02X328817Y134347I5509J0D01*
G01X328861Y134375D01*
X328910Y134464D01*
Y134906D01*
X328861Y134995D01*
X328817Y135023D01*
G02Y144347I2936J4662D01*
G01X328861Y144375D01*
X328910Y144464D01*
Y144906D01*
X328861Y144995D01*
X328817Y145023D01*
G02Y154347I2936J4662D01*
G01X328861Y154375D01*
X328910Y154464D01*
Y154906D01*
X328861Y154995D01*
X328817Y155023D01*
G02X326243Y159685I2935J4662D01*
G02X331752Y165194I5509J0D01*
G02X336414Y162620I0J-5509D01*
G01X336442Y162576D01*
X336531Y162527D01*
X336973D01*
X337062Y162576D01*
X337090Y162620D01*
G37*
G36*
G01X302090D02*
G02X306752Y165194I4662J-2935D01*
G02X312261Y159685I0J-5509D01*
G02X309687Y155023I-5509J0D01*
G01X309643Y154995D01*
X309594Y154906D01*
Y154464D01*
X309643Y154375D01*
X309687Y154347D01*
G02Y145023I-2936J-4662D01*
G01X309643Y144995D01*
X309594Y144906D01*
Y144464D01*
X309643Y144375D01*
X309687Y144347D01*
G02Y135023I-2936J-4662D01*
G01X309643Y134995D01*
X309594Y134906D01*
Y134464D01*
X309643Y134375D01*
X309687Y134347D01*
G02X312261Y129685I-2935J-4662D01*
G02X306752Y124176I-5509J0D01*
G02X302090Y126750I0J5509D01*
G01X302062Y126794D01*
X301973Y126843D01*
X301531D01*
X301442Y126794D01*
X301414Y126750D01*
G02X296752Y124176I-4662J2935D01*
G02X291243Y129685I0J5509D01*
G02X293817Y134347I5509J0D01*
G01X293861Y134375D01*
X293910Y134464D01*
Y134906D01*
X293861Y134995D01*
X293817Y135023D01*
G02Y144347I2936J4662D01*
G01X293861Y144375D01*
X293910Y144464D01*
Y144906D01*
X293861Y144995D01*
X293817Y145023D01*
G02Y154347I2936J4662D01*
G01X293861Y154375D01*
X293910Y154464D01*
Y154906D01*
X293861Y154995D01*
X293817Y155023D01*
G02X291243Y159685I2935J4662D01*
G02X296752Y165194I5509J0D01*
G02X301414Y162620I0J-5509D01*
G01X301442Y162576D01*
X301531Y162527D01*
X301973D01*
X302062Y162576D01*
X302090Y162620D01*
G37*
G36*
G01X425197Y22556D02*
G02Y71932I0J24688D01*
G01X511811D01*
G02Y22556I0J-24688D01*
G01X425197D01*
G37*
G36*
G01X185337Y209292D02*
G02X184349Y209149I-990J3359D01*
G02X183219Y209336I-1J3503D01*
G01X183188Y209347D01*
X176936D01*
G02X176794Y209406I0J200D01*
G01X169159Y217041D01*
G02X169100Y217183I141J142D01*
G01Y228417D01*
G02X169159Y228559I200J0D01*
G01X172241Y231641D01*
G02X172383Y231700I142J-141D01*
G01X178217D01*
G02X178359Y231641I0J-200D01*
G01X188041Y221959D01*
G02X188100Y221817I-141J-142D01*
G01Y210983D01*
G02X188041Y210841I-200J0D01*
G01X186559Y209359D01*
G02X186417Y209300I-142J141D01*
G01X185365D01*
X185337Y209292D01*
G37*
G36*
G01X1030500Y564688D02*
G02Y520312I0J-22188D01*
G01X943886D01*
G02Y564688I0J22188D01*
G01X1030500D01*
G37*
G36*
G01X586166Y447572D02*
G02X589500Y450002I3334J-1072D01*
G02X593002Y446500I0J-3502D01*
G02X590942Y443309I-3501J0D01*
G03X590834Y443188I82J-182D01*
G02X587500Y440758I-3334J1072D01*
G02X583998Y444260I0J3502D01*
G02X586058Y447451I3501J0D01*
G03X586166Y447572I-82J182D01*
G37*
G36*
G01X182120Y501202D02*
G02X183537Y501502I1418J-3202D01*
G01X183539D01*
G02Y494498I0J-3502D01*
G01X183537D01*
G02X182120Y494798I1J3502D01*
G03X181958I-81J-182D01*
G02X180541Y494498I-1418J3202D01*
G01X180539D01*
G02Y501502I0J3502D01*
G01X180541D01*
G02X181958Y501202I-1J-3502D01*
G03X182120I81J182D01*
G37*
G36*
G01X230120D02*
G02X231537Y501502I1418J-3202D01*
G01X231539D01*
G02Y494498I0J-3502D01*
G01X231537D01*
G02X230120Y494798I1J3502D01*
G03X229958I-81J-182D01*
G02X228541Y494498I-1418J3202D01*
G01X228539D01*
G02Y501502I0J3502D01*
G01X228541D01*
G02X229958Y501202I-1J-3502D01*
G03X230120I81J182D01*
G37*
G36*
G01X278120D02*
G02X279537Y501502I1418J-3202D01*
G01X279539D01*
G02Y494498I0J-3502D01*
G01X279537D01*
G02X278120Y494798I1J3502D01*
G03X277958I-81J-182D01*
G02X276541Y494498I-1418J3202D01*
G01X276539D01*
G02Y501502I0J3502D01*
G01X276541D01*
G02X277958Y501202I-1J-3502D01*
G03X278120I81J182D01*
G37*
G36*
G01X339600D02*
G02X341017Y501502I1418J-3202D01*
G01X341019D01*
G02Y494498I0J-3502D01*
G01X341017D01*
G02X339600Y494798I1J3502D01*
G03X339438I-81J-182D01*
G02X338021Y494498I-1418J3202D01*
G01X338019D01*
G02Y501502I0J3502D01*
G01X338021D01*
G02X339438Y501202I-1J-3502D01*
G03X339600I81J182D01*
G37*
G36*
G01X387600D02*
G02X389017Y501502I1418J-3202D01*
G01X389019D01*
G02Y494498I0J-3502D01*
G01X389017D01*
G02X387600Y494798I1J3502D01*
G03X387438I-81J-182D01*
G02X386021Y494498I-1418J3202D01*
G01X386019D01*
G02Y501502I0J3502D01*
G01X386021D01*
G02X387438Y501202I-1J-3502D01*
G03X387600I81J182D01*
G37*
G36*
G01X435600D02*
G02X437017Y501502I1418J-3202D01*
G01X437019D01*
G02Y494498I0J-3502D01*
G01X437017D01*
G02X435600Y494798I1J3502D01*
G03X435438I-81J-182D01*
G02X434021Y494498I-1418J3202D01*
G01X434019D01*
G02Y501502I0J3502D01*
G01X434021D01*
G02X435438Y501202I-1J-3502D01*
G03X435600I81J182D01*
G37*
G36*
G01X497081D02*
G02X498498Y501502I1418J-3202D01*
G01X498500D01*
G02Y494498I0J-3502D01*
G01X498498D01*
G02X497081Y494798I1J3502D01*
G03X496919I-81J-182D01*
G02X495502Y494498I-1418J3202D01*
G01X495500D01*
G02Y501502I0J3502D01*
G01X495502D01*
G02X496919Y501202I-1J-3502D01*
G03X497081I81J182D01*
G37*
G36*
G01X545081D02*
G02X546498Y501502I1418J-3202D01*
G01X546500D01*
G02Y494498I0J-3502D01*
G01X546498D01*
G02X545081Y494798I1J3502D01*
G03X544919I-81J-182D01*
G02X543502Y494498I-1418J3202D01*
G01X543500D01*
G02Y501502I0J3502D01*
G01X543502D01*
G02X544919Y501202I-1J-3502D01*
G03X545081I81J182D01*
G37*
G36*
G01X593081D02*
G02X594498Y501502I1418J-3202D01*
G01X594500D01*
G02Y494498I0J-3502D01*
G01X594498D01*
G02X593081Y494798I1J3502D01*
G03X592919I-81J-182D01*
G02X591502Y494498I-1418J3202D01*
G01X591500D01*
G02Y501502I0J3502D01*
G01X591502D01*
G02X592919Y501202I-1J-3502D01*
G03X593081I81J182D01*
G37*
G36*
G01X654562D02*
G02X655979Y501502I1418J-3202D01*
G01X655981D01*
G02Y494498I0J-3502D01*
G01X655979D01*
G02X654562Y494798I1J3502D01*
G03X654400I-81J-182D01*
G02X652983Y494498I-1418J3202D01*
G01X652981D01*
G02Y501502I0J3502D01*
G01X652983D01*
G02X654400Y501202I-1J-3502D01*
G03X654562I81J182D01*
G37*
G36*
G01X702562D02*
G02X703979Y501502I1418J-3202D01*
G01X703981D01*
G02Y494498I0J-3502D01*
G01X703979D01*
G02X702562Y494798I1J3502D01*
G03X702400I-81J-182D01*
G02X700983Y494498I-1418J3202D01*
G01X700981D01*
G02Y501502I0J3502D01*
G01X700983D01*
G02X702400Y501202I-1J-3502D01*
G03X702562I81J182D01*
G37*
G36*
G01X750562D02*
G02X751979Y501502I1418J-3202D01*
G01X751981D01*
G02Y494498I0J-3502D01*
G01X751979D01*
G02X750562Y494798I1J3502D01*
G03X750400I-81J-182D01*
G02X748983Y494498I-1418J3202D01*
G01X748981D01*
G02Y501502I0J3502D01*
G01X748983D01*
G02X750400Y501202I-1J-3502D01*
G03X750562I81J182D01*
G37*
G36*
G01X182120Y521202D02*
G02X183537Y521502I1418J-3202D01*
G01X183539D01*
G02Y514498I0J-3502D01*
G01X183537D01*
G02X182120Y514798I1J3502D01*
G03X181958I-81J-182D01*
G02X180541Y514498I-1418J3202D01*
G01X180539D01*
G02Y521502I0J3502D01*
G01X180541D01*
G02X181958Y521202I-1J-3502D01*
G03X182120I81J182D01*
G37*
G36*
G01X230120D02*
G02X231537Y521502I1418J-3202D01*
G01X231539D01*
G02Y514498I0J-3502D01*
G01X231537D01*
G02X230120Y514798I1J3502D01*
G03X229958I-81J-182D01*
G02X228541Y514498I-1418J3202D01*
G01X228539D01*
G02Y521502I0J3502D01*
G01X228541D01*
G02X229958Y521202I-1J-3502D01*
G03X230120I81J182D01*
G37*
G36*
G01X278120D02*
G02X279537Y521502I1418J-3202D01*
G01X279539D01*
G02Y514498I0J-3502D01*
G01X279537D01*
G02X278120Y514798I1J3502D01*
G03X277958I-81J-182D01*
G02X276541Y514498I-1418J3202D01*
G01X276539D01*
G02Y521502I0J3502D01*
G01X276541D01*
G02X277958Y521202I-1J-3502D01*
G03X278120I81J182D01*
G37*
G36*
G01X339600D02*
G02X341017Y521502I1418J-3202D01*
G01X341019D01*
G02Y514498I0J-3502D01*
G01X341017D01*
G02X339600Y514798I1J3502D01*
G03X339438I-81J-182D01*
G02X338021Y514498I-1418J3202D01*
G01X338019D01*
G02Y521502I0J3502D01*
G01X338021D01*
G02X339438Y521202I-1J-3502D01*
G03X339600I81J182D01*
G37*
G36*
G01X387600D02*
G02X389017Y521502I1418J-3202D01*
G01X389019D01*
G02Y514498I0J-3502D01*
G01X389017D01*
G02X387600Y514798I1J3502D01*
G03X387438I-81J-182D01*
G02X386021Y514498I-1418J3202D01*
G01X386019D01*
G02Y521502I0J3502D01*
G01X386021D01*
G02X387438Y521202I-1J-3502D01*
G03X387600I81J182D01*
G37*
G36*
G01X435600D02*
G02X437017Y521502I1418J-3202D01*
G01X437019D01*
G02Y514498I0J-3502D01*
G01X437017D01*
G02X435600Y514798I1J3502D01*
G03X435438I-81J-182D01*
G02X434021Y514498I-1418J3202D01*
G01X434019D01*
G02Y521502I0J3502D01*
G01X434021D01*
G02X435438Y521202I-1J-3502D01*
G03X435600I81J182D01*
G37*
G36*
G01X497081D02*
G02X498498Y521502I1418J-3202D01*
G01X498500D01*
G02Y514498I0J-3502D01*
G01X498498D01*
G02X497081Y514798I1J3502D01*
G03X496919I-81J-182D01*
G02X495502Y514498I-1418J3202D01*
G01X495500D01*
G02Y521502I0J3502D01*
G01X495502D01*
G02X496919Y521202I-1J-3502D01*
G03X497081I81J182D01*
G37*
G36*
G01X545081D02*
G02X546498Y521502I1418J-3202D01*
G01X546500D01*
G02Y514498I0J-3502D01*
G01X546498D01*
G02X545081Y514798I1J3502D01*
G03X544919I-81J-182D01*
G02X543502Y514498I-1418J3202D01*
G01X543500D01*
G02Y521502I0J3502D01*
G01X543502D01*
G02X544919Y521202I-1J-3502D01*
G03X545081I81J182D01*
G37*
G36*
G01X593081D02*
G02X594498Y521502I1418J-3202D01*
G01X594500D01*
G02Y514498I0J-3502D01*
G01X594498D01*
G02X593081Y514798I1J3502D01*
G03X592919I-81J-182D01*
G02X591502Y514498I-1418J3202D01*
G01X591500D01*
G02Y521502I0J3502D01*
G01X591502D01*
G02X592919Y521202I-1J-3502D01*
G03X593081I81J182D01*
G37*
G36*
G01X654562D02*
G02X655979Y521502I1418J-3202D01*
G01X655981D01*
G02Y514498I0J-3502D01*
G01X655979D01*
G02X654562Y514798I1J3502D01*
G03X654400I-81J-182D01*
G02X652983Y514498I-1418J3202D01*
G01X652981D01*
G02Y521502I0J3502D01*
G01X652983D01*
G02X654400Y521202I-1J-3502D01*
G03X654562I81J182D01*
G37*
G36*
G01X702562D02*
G02X703979Y521502I1418J-3202D01*
G01X703981D01*
G02Y514498I0J-3502D01*
G01X703979D01*
G02X702562Y514798I1J3502D01*
G03X702400I-81J-182D01*
G02X700983Y514498I-1418J3202D01*
G01X700981D01*
G02Y521502I0J3502D01*
G01X700983D01*
G02X702400Y521202I-1J-3502D01*
G03X702562I81J182D01*
G37*
G36*
G01X750562D02*
G02X751979Y521502I1418J-3202D01*
G01X751981D01*
G02Y514498I0J-3502D01*
G01X751979D01*
G02X750562Y514798I1J3502D01*
G03X750400I-81J-182D01*
G02X748983Y514498I-1418J3202D01*
G01X748981D01*
G02Y521502I0J3502D01*
G01X748983D01*
G02X750400Y521202I-1J-3502D01*
G03X750562I81J182D01*
G37*
G36*
G01X576611Y282048D02*
X576622Y282064D01*
G02X583780Y285856I7158J-4860D01*
G02Y268552I0J-8652D01*
G02X576622Y272344I0J8652D01*
G01X576611Y272360D01*
X576582Y272389D01*
G03X576440Y272448I-142J-141D01*
G01X576120D01*
G03X575978Y272389I0J-200D01*
G01X575949Y272360D01*
X575938Y272344D01*
G02X568780Y268552I-7158J4860D01*
G02X565688Y269124I2J8652D01*
G03X565469Y269072I-71J-187D01*
G01X565237Y268818D01*
G03X565185Y268684I148J-135D01*
G01Y268592D01*
G02X565512Y267204I-2782J-1388D01*
G02X562402Y270314I-3110J0D01*
G02X562535Y270311I-4J-3110D01*
G01X562607Y270347D01*
X562638Y270389D01*
X562653Y270409D01*
X562803Y270771D01*
G03X562758Y270991I-185J77D01*
G02X560128Y277203I6022J6212D01*
G01Y277204D01*
G02X568780Y285856I8652J0D01*
G02X575938Y282064I0J-8652D01*
G01X575949Y282048D01*
X575978Y282019D01*
G03X576120Y281960I142J141D01*
G01X576440D01*
G03X576582Y282019I0J200D01*
G01X576611Y282048D01*
G37*
G36*
G01X734092D02*
X734103Y282064D01*
G02X741261Y285856I7158J-4860D01*
G02Y268552I0J-8652D01*
G02X734103Y272344I0J8652D01*
G01X734092Y272360D01*
X734063Y272389D01*
G03X733921Y272448I-142J-141D01*
G01X733601D01*
G03X733459Y272389I0J-200D01*
G01X733430Y272360D01*
X733419Y272344D01*
G02X726261Y268552I-7158J4860D01*
G02X723169Y269124I2J8652D01*
G03X722950Y269072I-71J-187D01*
G01X722718Y268818D01*
G03X722666Y268684I148J-135D01*
G01Y268592D01*
G02X722993Y267204I-2782J-1388D01*
G02X719883Y270314I-3110J0D01*
G02X720011Y270311I-9J-3110D01*
G01X720066Y270333D01*
X720096Y270362D01*
G03X720142Y270429I-138J144D01*
G01X720284Y270771D01*
G03X720239Y270991I-185J77D01*
G02X717609Y277203I6022J6212D01*
G01Y277204D01*
G02X726261Y285856I8652J0D01*
G02X733419Y282064I0J-8652D01*
G01X733430Y282048D01*
X733459Y282019D01*
G03X733601Y281960I142J141D01*
G01X733921D01*
G03X734063Y282019I0J200D01*
G01X734092Y282048D01*
G37*
G36*
G01X751084Y33342D02*
G03X751236I76J185D01*
G02X752560Y33602I1324J-3241D01*
G02X756062Y30100I0J-3502D01*
G02X753889Y26860I-3502J0D01*
G03X753767Y26703I76J-185D01*
G02X750300Y23698I-3467J498D01*
G02X746897Y26373I0J3502D01*
G01Y26374D01*
G03X746836Y26475I-194J-48D01*
G01X746835Y26476D01*
G03X746728Y26525I-133J-149D01*
G01X746727D01*
G02X743658Y30000I433J3475D01*
G02X747160Y33502I3502J0D01*
G01X747164D01*
G02X748266Y33324I0J-3503D01*
G03X748395I65J190D01*
G03X748407Y33329I-71J187D01*
G02X749759Y33602I1356J-3229D01*
G01X749760D01*
G02X751084Y33342I0J-3501D01*
G37*
G36*
G01Y41842D02*
G03X751236I76J185D01*
G02X752560Y42102I1324J-3241D01*
G02Y35098I0J-3502D01*
G02X751236Y35358I0J3501D01*
G03X751084I-76J-185D01*
G02X749760Y35098I-1324J3241D01*
G01X749756D01*
G02X748654Y35276I0J3503D01*
G03X748525I-64J-190D01*
G03X748513Y35271I71J-187D01*
G02X747161Y34998I-1356J3229D01*
G01X747160D01*
G02Y42002I0J3502D01*
G01X747164D01*
G02X748266Y41824I0J-3503D01*
G03X748395I65J190D01*
G03X748407Y41829I-71J187D01*
G02X749759Y42102I1356J-3229D01*
G01X749760D01*
G02X751084Y41842I0J-3501D01*
G37*
G36*
G01Y50342D02*
G03X751236I76J185D01*
G02X752560Y50602I1324J-3241D01*
G02Y43598I0J-3502D01*
G02X751236Y43858I0J3501D01*
G03X751084I-76J-185D01*
G02X749760Y43598I-1324J3241D01*
G01X749756D01*
G02X748654Y43776I0J3503D01*
G03X748525I-64J-190D01*
G03X748513Y43771I71J-187D01*
G02X747161Y43498I-1356J3229D01*
G01X747160D01*
G02Y50502I0J3502D01*
G01X747164D01*
G02X748266Y50324I0J-3503D01*
G03X748395I65J190D01*
G03X748407Y50329I-71J187D01*
G02X749759Y50602I1356J-3229D01*
G01X749760D01*
G02X751084Y50342I0J-3501D01*
G37*
G36*
G01Y58842D02*
G03X751236I76J185D01*
G02X752560Y59102I1324J-3241D01*
G02Y52098I0J-3502D01*
G02X751236Y52358I0J3501D01*
G03X751084I-76J-185D01*
G02X749760Y52098I-1324J3241D01*
G01X749756D01*
G02X748654Y52276I0J3503D01*
G03X748525I-64J-190D01*
G03X748513Y52271I71J-187D01*
G02X747161Y51998I-1356J3229D01*
G01X747160D01*
G02Y59002I0J3502D01*
G01X747164D01*
G02X748266Y58824I0J-3503D01*
G03X748395I65J190D01*
G03X748407Y58829I-71J187D01*
G02X749759Y59102I1356J-3229D01*
G01X749760D01*
G02X751084Y58842I0J-3501D01*
G37*
G36*
G01Y67342D02*
G03X751236I76J185D01*
G02X752560Y67602I1324J-3241D01*
G02Y60598I0J-3502D01*
G02X751236Y60858I0J3501D01*
G03X751084I-76J-185D01*
G02X749760Y60598I-1324J3241D01*
G01X749756D01*
G02X748654Y60776I0J3503D01*
G03X748525I-64J-190D01*
G03X748513Y60771I71J-187D01*
G02X747161Y60498I-1356J3229D01*
G01X747160D01*
G02Y67502I0J3502D01*
G01X747164D01*
G02X748266Y67324I0J-3503D01*
G03X748395I65J190D01*
G03X748407Y67329I-71J187D01*
G02X749759Y67602I1356J-3229D01*
G01X749760D01*
G02X751084Y67342I0J-3501D01*
G37*
G36*
G01X1075092Y93848D02*
G03X1075308I108J168D01*
G02X1077200Y94403I1892J-2947D01*
G02Y87397I0J-3503D01*
G02X1075308Y87952I0J3502D01*
G03X1075092I-108J-168D01*
G02X1073200Y87397I-1892J2947D01*
G02Y94403I0J3503D01*
G02X1075092Y93848I0J-3502D01*
G37*
G36*
G01X512056Y267204D02*
G02X512629Y269000I3101J0D01*
G02X517687I2529J-1796D01*
G02X518260Y267204I-2528J-1796D01*
G02X512056I-3102J0D01*
G37*
G36*
G01X848662Y273133D02*
X848690Y273158D01*
G02X852974Y273418I2310J-2634D01*
G02X853312Y273157I-1968J-2898D01*
G01X853340Y273133D01*
X853406Y273108D01*
X853595D01*
X853662Y273133D01*
X853690Y273158D01*
G02X855999Y274027I2309J-2634D01*
G01X856000D01*
G02Y267023I0J-3502D01*
G02X854534Y267345I1J3503D01*
G03X854339Y267329I-83J-182D01*
G02X852662I-839J1245D01*
G03X852466Y267345I-112J-166D01*
G02X851000Y267023I-1467J3181D01*
G01X850999D01*
G02X848690Y267892I0J3503D01*
G01X848662Y267917D01*
X848595Y267942D01*
X848405D01*
X848338Y267917D01*
X848310Y267892D01*
G02X846001Y267023I-2309J2634D01*
G01X846000D01*
G02X845529Y267055I1J3502D01*
G01X845522Y267056D01*
X845485Y267061D01*
G02X844535Y267345I518J3464D01*
G03X844433Y267363I-85J-181D01*
G01X844380Y267358D01*
G02X843501Y267073I-880J1216D01*
G01X843500D01*
G02X842681Y267316I0J1502D01*
G03X842487Y267329I-109J-168D01*
G02X841001Y266998I-1486J3171D01*
G01X840999D01*
G02X838690Y267867I0J3503D01*
G01X838662Y267892D01*
X838595Y267917D01*
X838405D01*
X838338Y267892D01*
X838310Y267867D01*
G02X836001Y266998I-2309J2634D01*
G01X835999D01*
G02X834513Y267329I0J3502D01*
G03X834319Y267316I-85J-181D01*
G02X832681I-819J1259D01*
G03X832487Y267329I-109J-168D01*
G02X831002Y266998I-1486J3171D01*
G01X831000D01*
G02X828677Y267879I0J3503D01*
G01X828649Y267904D01*
X828583Y267929D01*
X828430Y267930D01*
G03X828324Y267901I-2J-200D01*
G01X828307Y267890D01*
X828295Y267880D01*
G02X826000Y267023I-2296J2646D01*
G02X822714Y269313I0J3503D01*
G01X822705Y269337D01*
X822678Y269377D01*
X822658Y269394D01*
G03X822569Y269439I-132J-150D01*
G01X822241Y269511D01*
G03X822059Y269459I-43J-195D01*
G01X822058Y269458D01*
G02X821001Y269023I-1057J1067D01*
G01X821000D01*
G02Y272027I0J1502D01*
G01X821001D01*
G02X822057Y271593I0J-1502D01*
G03X822059Y271591I142J140D01*
G03X822241Y271539I139J143D01*
G01X822569Y271611D01*
G03X822658Y271656I-43J195D01*
G01X822678Y271673D01*
X822705Y271713D01*
X822714Y271737D01*
G02X826000Y274027I3286J-1213D01*
G02X828323Y273146I0J-3503D01*
G01X828351Y273121D01*
X828417Y273096D01*
X828570Y273095D01*
G03X828676Y273124I2J200D01*
G01X828693Y273135D01*
X828705Y273145D01*
G02X831000Y274002I2296J-2646D01*
G01X831001D01*
G02X833310Y273133I0J-3503D01*
G01X833338Y273108D01*
X833405Y273083D01*
X833595D01*
X833662Y273108D01*
X833690Y273133D01*
G02X838310I2310J-2634D01*
G01X838338Y273108D01*
X838405Y273083D01*
X838595D01*
X838662Y273108D01*
X838690Y273133D01*
G02X840999Y274002I2309J-2634D01*
G01X841000D01*
G02X843292Y273147I-1J-3503D01*
G01X843318Y273123D01*
X843389Y273095D01*
X843583Y273096D01*
X843649Y273121D01*
X843677Y273146D01*
G02X846000Y274027I2323J-2622D01*
G01X846001D01*
G02X848310Y273158I0J-3503D01*
G01X848338Y273133D01*
X848405Y273108D01*
X848595D01*
X848662Y273133D01*
G37*
G36*
G01X803900Y275922D02*
G02Y282928I0J3503D01*
G02X807376Y279859I0J-3503D01*
G03X807847Y279516I397J50D01*
G02X808496Y279577I651J-3441D01*
G01X808500D01*
G02X812002Y276075I0J-3502D01*
G02X810105Y272962I-3503J0D01*
G03X809997Y272801I91J-178D01*
G02X807003I-1497J124D01*
G03X806895Y272962I-199J-17D01*
G02X805025Y275640I1606J3113D01*
G03X804554Y275984I-397J-49D01*
G02X803900Y275922I-656J3441D01*
G37*
G36*
G01X440391Y286133D02*
G03X440607I108J168D01*
G02X442499Y286688I1892J-2947D01*
G02X446001Y283186I0J-3502D01*
G02X445446Y281294I-3502J0D01*
G03Y281078I168J-108D01*
G02Y277294I-2948J-1892D01*
G03Y277078I168J-108D01*
G02Y273294I-2948J-1892D01*
G03Y273078I168J-108D01*
G02X446001Y271186I-2947J-1892D01*
G02X442499Y267684I-3502J0D01*
G02X440607Y268239I0J3502D01*
G03X440391I-108J-168D01*
G02X436607I-1892J2948D01*
G03X436391I-108J-168D01*
G02X434499Y267684I-1892J2947D01*
G02X431353Y269643I0J3506D01*
G01X431334Y269681D01*
X431270Y269735D01*
X430948Y269829D01*
G03X430790Y269809I-56J-192D01*
G01X430789Y269808D01*
G02X426300Y268552I-4490J7396D01*
G01X426299D01*
G02X419141Y272344I0J8652D01*
G01X419130Y272360D01*
X419101Y272389D01*
G03X418959Y272448I-142J-141D01*
G01X418639D01*
G03X418497Y272389I0J-200D01*
G01X418468Y272360D01*
X418457Y272344D01*
G02X411299Y268552I-7158J4860D01*
G02X408241Y269111I1J8652D01*
G01X408207Y269124D01*
X408123D01*
G03X407976Y269059I1J-200D01*
G01X407757Y268821D01*
G03X407704Y268686I147J-136D01*
G01Y268594D01*
X407713Y268552D01*
X407723Y268531D01*
G02X408023Y267204I-2801J-1331D01*
G02X404921Y270306I-3102J0D01*
G01X404924D01*
G02X404972Y270305I-41J-3101D01*
G01X404991D01*
X405039Y270304D01*
X405126Y270347D01*
X405157Y270389D01*
X405172Y270409D01*
X405322Y270771D01*
G03X405277Y270991I-185J77D01*
G02X402647Y277203I6022J6212D01*
G01Y277204D01*
G02X411299Y285856I8652J0D01*
G02X418457Y282064I0J-8652D01*
G01X418468Y282048D01*
X418497Y282019D01*
G03X418639Y281960I142J141D01*
G01X418959D01*
G03X419101Y282019I0J200D01*
G01X419130Y282048D01*
X419141Y282064D01*
G02X426299Y285856I7158J-4860D01*
G02X430802Y284592I0J-8653D01*
G01X430838Y284570D01*
X430920Y284559D01*
X431194Y284638D01*
X431210Y284646D01*
X431308Y284694D01*
X431370Y284756D01*
X431385Y284784D01*
G02X434499Y286688I3114J-1594D01*
G02X436391Y286133I0J-3502D01*
G03X436607I108J168D01*
G02X440391I1892J-2948D01*
G37*
G36*
G01X219931Y313162D02*
X219937Y313206D01*
G02X221425Y314502I1488J-206D01*
G02X222927Y313000I0J-1502D01*
G02X221905Y311576I-1503J0D01*
G01X221892Y311572D01*
X221833Y311544D01*
X221783Y311491D01*
X221769Y311457D01*
X221672Y311231D01*
G03X221656Y311153I184J-78D01*
G01Y311024D01*
X221675Y310984D01*
G02X222002Y309505I-3176J-1478D01*
G01Y309500D01*
G02X218500Y313002I-3502J0D01*
G02X219418Y312878I-6J-3501D01*
G02X219425Y312876I-51J-193D01*
G03X219593Y312900I58J192D01*
G01X219885Y313090D01*
X219931Y313162D01*
G37*
G36*
G01X696239Y314630D02*
G02X697099Y314902I862J-1230D01*
G01X697100D01*
G02X698022Y314586I0J-1503D01*
G01X698032Y314578D01*
G02X698361Y314216I-932J-1178D01*
G02X699956Y314544I1595J-3716D01*
G02X695912Y310500I0J-4044D01*
G02X696265Y312151I4044J-1D01*
G02X696233Y312173I835J1249D01*
G02X695598Y313400I868J1227D01*
G02X696181Y314588I1502J0D01*
G01X696206Y314607D01*
X696239Y314630D01*
G37*
G36*
G01X228990Y313162D02*
G02X228923Y313605I1435J444D01*
G02X230425Y312103I1502J0D01*
G02X230236Y312115I0J1502D01*
G03X229856Y311491I-51J-397D01*
G02X230477Y309500I-2881J-1991D01*
G02X226975Y313002I-3502J0D01*
G01X226976D01*
G02X228440Y312681I-1J-3502D01*
G03X228990Y313162I168J363D01*
G37*
G36*
G01X381461Y316398D02*
Y316400D01*
G02X384465I1502J0D01*
G01Y316398D01*
G02X384055Y315369I-1502J2D01*
G03X384047Y315360I145J-137D01*
G02X384039Y315351I-153J128D01*
G01X384012Y315323D01*
X383984Y315252D01*
Y314898D01*
X384013Y314826D01*
X384040Y314797D01*
G02X384465Y313752I-1077J-1047D01*
G01Y313750D01*
G02X384429Y313425I-1502J2D01*
G01X384424Y313403D01*
Y313350D01*
G03X384431Y313296I200J-2D01*
G01X384439Y313269D01*
X384456Y313239D01*
X384599Y313012D01*
G03X384622Y312982I170J106D01*
G01X384646Y312957D01*
X384671Y312942D01*
G03X384728Y312920I100J173D01*
G02X387477Y309500I-753J-3420D01*
G02X380473I-3502J0D01*
G02X381753Y312207I3502J0D01*
G01X381761Y312213D01*
X381778Y312230D01*
G03X381835Y312353I-142J141D01*
G01X381865Y312676D01*
X381841Y312751D01*
X381815Y312782D01*
G02X381461Y313750I1148J968D01*
G01Y313752D01*
G02X381871Y314781I1502J-2D01*
G03X381879Y314790I-145J137D01*
G02X381887Y314799I153J-128D01*
G01X381914Y314827D01*
X381942Y314898D01*
Y315252D01*
X381913Y315324D01*
X381886Y315353D01*
G02X381461Y316398I1077J1047D01*
G37*
G36*
G01X538696Y315215D02*
G02X538117Y316400I923J1185D01*
G02X541121I1502J0D01*
G02X540542Y315215I-1502J0D01*
G03X540465Y315058I123J-158D01*
G01Y314742D01*
G03X540542Y314585I200J1D01*
G02X541003Y313984I-923J-1185D01*
G01Y313983D01*
G03X541102Y313881I184J79D01*
G01X541215Y313828D01*
G03X541289Y313810I83J182D01*
G01X541326Y313808D01*
X541363Y313820D01*
X541364D01*
G02X542475Y314002I1114J-3320D01*
G02X538973Y310500I0J-3502D01*
G01Y310503D01*
G02X539172Y311664I3502J-3D01*
G01Y311665D01*
G03X539181Y311758I-189J65D01*
G01X539177Y311790D01*
X539101Y311957D01*
X539048Y312010D01*
X539014Y312025D01*
G02X538117Y313400I605J1375D01*
G02X538696Y314585I1502J0D01*
G03X538773Y314742I-123J158D01*
G01Y315058D01*
G03X538696Y315215I-200J-1D01*
G37*
G36*
G01X733214Y326884D02*
G03X733861I323J236D01*
G02X735075Y327502I1214J-883D01*
G02Y324498I0J-1502D01*
G02X733861Y325116I0J1501D01*
G03X733214I-324J-236D01*
G02X732000Y324498I-1214J883D01*
G02Y327502I0J1502D01*
G02X733214Y326884I0J-1501D01*
G37*
G36*
G01X733169Y336842D02*
G03X733831I331J224D01*
G02X735075Y337502I1244J-842D01*
G02Y334498I0J-1502D01*
G02X733831Y335158I0J1502D01*
G03X733169I-331J-224D01*
G02X731925Y334498I-1244J842D01*
G02Y337502I0J1502D01*
G02X733169Y336842I0J-1502D01*
G37*
G36*
G01X740009Y350739D02*
G02X738998Y353200I2490J2461D01*
G02X746002I3502J0D01*
G02X744984Y350732I-3501J0D01*
G03X744926Y350591I142J-141D01*
G01Y350311D01*
X744935Y350267D01*
X744941Y350236D01*
X744968Y350184D01*
X744991Y350161D01*
G02X746002Y347700I-2490J-2461D01*
G02X744384Y344747I-3504J0D01*
G01X744344Y344722D01*
X744296Y344642D01*
X744262Y344233D01*
X744292Y344152D01*
X744341Y344103D01*
G02X745502Y341500I-2338J-2603D01*
G02X743753Y338468I-3503J0D01*
G01X743702Y338439D01*
X743649Y338338D01*
X743679Y337927D01*
G03X743680Y337920I198J25D01*
G03X743737Y337800I199J21D01*
G01X743776Y337761D01*
X743814Y337746D01*
G02X746002Y334500I-1314J-3246D01*
G02X744739Y331808I-3502J1D01*
G03X744667Y331655I128J-154D01*
G01Y331347D01*
G03X744724Y331207I200J0D01*
G01X744741Y331190D01*
X744748Y331184D01*
G02X746002Y328500I-2248J-2685D01*
G02X745447Y326608I-3502J0D01*
G03Y326392I168J-108D01*
G02X746002Y324500I-2947J-1892D01*
G02X738998I-3502J0D01*
G02X739553Y326392I3502J0D01*
G03Y326608I-168J108D01*
G02X738998Y328500I2947J1892D01*
G02X740261Y331192I3502J-1D01*
G03X740333Y331345I-128J154D01*
G01Y331653D01*
G03X740276Y331793I-200J0D01*
G01X740259Y331810D01*
X740252Y331816D01*
G02X738998Y334500I2248J2685D01*
G02X740747Y337532I3503J0D01*
G01X740798Y337561D01*
X740851Y337662D01*
X740821Y338073D01*
G03X740820Y338080I-198J-25D01*
G03X740763Y338200I-199J-21D01*
G01X740724Y338239D01*
X740686Y338254D01*
G02X738498Y341500I1314J3246D01*
G02X740116Y344453I3504J0D01*
G01X740156Y344478D01*
X740204Y344558D01*
X740238Y344967D01*
X740208Y345048D01*
X740159Y345097D01*
G02X738998Y347700I2338J2603D01*
G02X740016Y350168I3501J0D01*
G03X740074Y350309I-142J141D01*
G01Y350589D01*
X740065Y350633D01*
X740059Y350664D01*
X740032Y350716D01*
X740009Y350739D01*
G37*
G36*
G01X808425Y347502D02*
G02X811538Y345605I0J-3503D01*
G03X811699Y345497I178J91D01*
G02Y342503I-124J-1497D01*
G03X811538Y342395I17J-199D01*
G02X808425Y347502I-3113J1605D01*
G37*
G36*
G01X827000Y356002D02*
X827002D01*
G02X828122Y355818I0J-3502D01*
G03X828340Y355880I64J189D01*
G02X829500Y356427I1160J-956D01*
G02X831002Y354925I0J-1502D01*
G02X830419Y353737I-1502J0D01*
G03X830350Y353520I122J-158D01*
G02X830502Y352500I-3350J-1021D01*
G02X827000Y356002I-3502J0D01*
G37*
G36*
G01X884000Y286977D02*
G02X885892Y286422I0J-3502D01*
G03X886108I108J168D01*
G02X888000Y286977I1892J-2947D01*
G02X890917Y285413I0J-3502D01*
G01X890945Y285372D01*
X891033Y285324D01*
X891467D01*
X891555Y285372D01*
X891583Y285413D01*
G02X894500Y286977I2917J-1938D01*
G02Y279973I0J-3502D01*
G02X891583Y281537I0J3502D01*
G01X891555Y281578D01*
X891467Y281626D01*
X891033D01*
X890945Y281578D01*
X890917Y281537D01*
G02X888000Y279973I-2917J1938D01*
G02X886108Y280528I0J3502D01*
G03X885892I-108J-168D01*
G02X884000Y279973I-1892J2947D01*
G02X881083Y281537I0J3502D01*
G01X881055Y281578D01*
X880967Y281626D01*
X880533D01*
X880445Y281578D01*
X880417Y281537D01*
G02X877500Y279973I-2917J1938D01*
G02Y286977I0J3502D01*
G02X880417Y285413I0J-3502D01*
G01X880445Y285372D01*
X880533Y285324D01*
X880967D01*
X881055Y285372D01*
X881083Y285413D01*
G02X884000Y286977I2917J-1938D01*
G37*
G36*
G01X905000D02*
G02X906892Y286422I0J-3502D01*
G03X907108I108J168D01*
G02X909000Y286977I1892J-2947D01*
G02X911917Y285413I0J-3502D01*
G01X911945Y285372D01*
X912033Y285324D01*
X912467D01*
X912555Y285372D01*
X912583Y285413D01*
G02X915500Y286977I2917J-1938D01*
G02Y279973I0J-3502D01*
G02X912583Y281537I0J3502D01*
G01X912555Y281578D01*
X912467Y281626D01*
X912033D01*
X911945Y281578D01*
X911917Y281537D01*
G02X909000Y279973I-2917J1938D01*
G02X907108Y280528I0J3502D01*
G03X906892I-108J-168D01*
G02X905000Y279973I-1892J2947D01*
G02Y286977I0J3502D01*
G37*
G36*
G01X936321Y294913D02*
X936679D01*
G03X936859Y295025I0J200D01*
G02X943141I3141J-1550D01*
G03X943321Y294913I180J88D01*
G01X943679D01*
G03X943859Y295025I0J200D01*
G02X947000Y296978I3141J-1549D01*
G02Y289974I0J-3502D01*
G02X943859Y291927I0J3502D01*
G03X943679Y292039I-180J-88D01*
G01X943321D01*
G03X943141Y291927I0J-200D01*
G02X936859I-3141J1550D01*
G03X936679Y292039I-180J-88D01*
G01X936321D01*
G03X936141Y291927I0J-200D01*
G02X933000Y289974I-3141J1549D01*
G02Y296978I0J3502D01*
G02X936141Y295025I0J-3502D01*
G03X936321Y294913I180J88D01*
G37*
G36*
G01X908000Y331477D02*
G02X910128Y330756I0J-3502D01*
G03X910372I122J159D01*
G02X912499Y331477I2128J-2781D01*
G01X912500D01*
G02Y324473I0J-3502D01*
G01X912499D01*
G02X910372Y325194I1J3502D01*
G03X910128I-122J-159D01*
G02X908000Y324473I-2128J2781D01*
G02X905872Y325194I0J3502D01*
G03X905628I-122J-159D01*
G02X903501Y324473I-2128J2781D01*
G01X903500D01*
G02Y331477I0J3502D01*
G01X903501D01*
G02X905628Y330756I-1J-3502D01*
G03X905872I122J159D01*
G02X908000Y331477I2128J-2781D01*
G37*
G36*
G01X848500Y332298D02*
G02X846508Y332920I0J3502D01*
G03X846306Y332935I-114J-165D01*
G02X844760Y332575I-1547J3143D01*
G02Y339579I0J3502D01*
G02X846752Y338957I0J-3502D01*
G03X846954Y338942I114J165D01*
G02X848500Y339302I1547J-3143D01*
G02Y332298I0J-3502D01*
G37*
G36*
G01X1161608Y174886D02*
X1161272Y174889D01*
X1161205Y174865D01*
X1161177Y174841D01*
G02X1160200Y174480I-977J1142D01*
G02Y177484I0J1502D01*
G02X1161198Y177105I0J-1502D01*
G01X1161225Y177080D01*
X1161292Y177055D01*
X1161628Y177052D01*
X1161695Y177076D01*
X1161723Y177100D01*
G02X1162700Y177461I977J-1142D01*
G02Y174457I0J-1502D01*
G02X1161702Y174836I0J1502D01*
G01X1161675Y174861D01*
X1161608Y174886D01*
G37*
G54D37*
X694425Y29500D03*
X707000Y32000D03*
X690075Y39500D03*
X703740Y41000D03*
Y54118D03*
X1022575Y100925D03*
Y115500D03*
X850750Y250750D03*
X806000Y265075D03*
X794900Y265979D03*
X816000Y270525D03*
X827602Y283500D03*
X724000Y294500D03*
X518575Y295500D03*
X694406D03*
X203575Y297500D03*
X676075Y299600D03*
X836500Y302500D03*
X845000Y303000D03*
X853000Y303500D03*
X861600Y304600D03*
X212925Y315500D03*
X779100Y326820D03*
X697900Y352500D03*
X754000Y353500D03*
X1152781Y165719D03*
G54D40*
X1087000Y100000D03*
X863600Y208900D03*
X784855Y265184D03*
X806500Y285500D03*
X814500Y293000D03*
X680400Y310500D03*
X786500Y316700D03*
G54D31*
X268000Y240000D03*
X312500D03*
X357000D03*
X428500D03*
X472500D03*
X516500D03*
X578500D03*
X622500D03*
X666500D03*
X735981D03*
X779981D03*
X823981D03*
X549500Y445024D03*
X1060984Y418742D03*
X1074316Y406925D03*
X1061600Y359642D03*
X223819Y445025D03*
X538780D03*
X381299D03*
X1067730Y460352D03*
X1061600Y466242D03*
Y323742D03*
Y276242D03*
Y513742D03*
X1067866Y507629D03*
X1067707Y365442D03*
X1067701Y270442D03*
X1067679Y317942D03*
X1067531Y412942D03*
X473095Y340339D03*
X313571Y340552D03*
X447255Y340339D03*
X173265Y340552D03*
X545063Y340339D03*
X290720Y340338D03*
X430019Y444260D03*
X432019Y452025D03*
X696261Y445024D03*
X247441Y305975D03*
X361000D03*
X404921D03*
X562402D03*
X719883D03*
X235975Y309500D03*
X375500D03*
X392975D03*
X533475Y310500D03*
X551475D03*
X690956D03*
X708956D03*
X901063Y352340D03*
X916260Y337077D03*
X905941Y320366D03*
X933357Y344843D03*
X933196Y353360D03*
X916260Y355000D03*
X923740Y345500D03*
X943171Y315385D03*
X941035Y344474D03*
X914500Y292000D03*
X933196Y309910D03*
X940575Y304000D03*
X940000Y283800D03*
X905941Y306500D03*
X893363Y298740D03*
X883000Y293925D03*
X880000Y312855D03*
X819500Y329000D03*
X827500D03*
X825941Y339560D03*
X835610Y355590D03*
X843843Y354342D03*
X875000Y347273D03*
X808425Y334000D03*
G54D44*
X357677Y267204D03*
X365551D03*
X373425D03*
X381299D03*
X389173D03*
X397047D03*
X523032D03*
X530906D03*
X538780D03*
X546654D03*
X554528D03*
X672639D03*
X680513D03*
X688387D03*
X696261D03*
X704135D03*
X712009D03*
G54D38*
X1092000Y82500D03*
G54D35*
X165539Y539000D03*
X213539D03*
X261539D03*
X323019D03*
X371019D03*
X419019D03*
X480500D03*
X528500D03*
X576500D03*
X637981D03*
X685981D03*
X733981D03*
G54D41*
X812559Y119408D03*
X822559D03*
X832559D03*
X812559Y129408D03*
X822559D03*
X832559D03*
X822559Y139408D03*
X832559D03*
X812559Y149408D03*
X822559D03*
X832559D03*
G54D39*
X1151000Y90400D03*
X1161000D03*
X1171000D03*
X1011000Y98000D03*
Y118000D03*
G54D30*
X268000Y220315D03*
X312500D03*
X357000D03*
X428500D03*
X472500D03*
X516500D03*
X578500D03*
X622500D03*
X666500D03*
X735981D03*
X779981D03*
X823981D03*
G54D36*
X185224Y539000D03*
X233224D03*
X281224D03*
X342704D03*
X390704D03*
X438704D03*
X500185D03*
X548185D03*
X596185D03*
X657666D03*
X705666D03*
X753666D03*
G54D33*
X253819Y477204D03*
X411299D03*
X568780D03*
X726261D03*
G54D32*
X253819Y277204D03*
X268819D03*
X336299D03*
X351299D03*
X493780D03*
X508780D03*
X651261D03*
X666261D03*
G54D34*
X193819Y477204D03*
X223819D03*
X351299D03*
X381299D03*
X508780D03*
X538780D03*
X666261D03*
X696261D03*
G54D29*
X249252Y129685D03*
X529252D03*
X665059Y149408D03*
G54D43*
X1226024Y174429D03*
Y399429D03*
G54D28*
X175000Y100500D03*
X964460Y16950D03*
G54D42*
X980059Y149408D03*
%LPD*%
G75*
G54D10*
G01X35679Y229497D02*
X38780Y232598D01*
G01X35679Y235699D02*
X38780Y232598D01*
G01X35679Y236190D02*
X38780Y239291D01*
G01X35679Y242392D02*
X38780Y239291D01*
G01X35679Y249497D02*
X38780Y252598D01*
G01X35679Y255699D02*
X38780Y252598D01*
G01X35679Y256190D02*
X38780Y259291D01*
G01X35679Y262392D02*
X38780Y259291D01*
G01X35679Y269497D02*
X38780Y272598D01*
G01X35679Y275699D02*
X38780Y272598D01*
G01X35679Y276190D02*
X38780Y279291D01*
G01X35679Y282392D02*
X38780Y279291D01*
G01X35679Y289497D02*
X38780Y292598D01*
G01X35679Y295699D02*
X38780Y292598D01*
G01X35679Y296190D02*
X38780Y299291D01*
G01X35679Y302392D02*
X38780Y299291D01*
G01Y232598D02*
X41881Y235699D01*
G01X38780Y232598D02*
X41881Y229497D01*
G01X45679Y249497D02*
X48780Y252598D01*
G01D02*
X51881Y249497D01*
G01X45679Y229497D02*
X48780Y232598D01*
G01D02*
X51881Y235699D01*
G01X45679D02*
X48780Y232598D01*
G01D02*
X51881Y229497D01*
G01X45679Y236190D02*
X48780Y239291D01*
G01D02*
X51881Y242392D01*
G01X45679D02*
X48780Y239291D01*
G01D02*
X51881Y236190D01*
G01X38780Y239291D02*
X41881Y242392D01*
G01X38780Y239291D02*
X41881Y236190D01*
G01X38780Y252598D02*
X41881Y249497D01*
G01X45679Y256190D02*
X48780Y259291D01*
G01D02*
X51881Y262392D01*
G01X45679D02*
X48780Y259291D01*
G01D02*
X51881Y256190D01*
G01X48780Y252598D02*
X51881Y255699D01*
G01X45679D02*
X48780Y252598D01*
G01X38780D02*
X41881Y255699D01*
G01X38780Y259291D02*
X41881Y262392D01*
G01X38780Y259291D02*
X41881Y256190D01*
G01X38780Y272598D02*
X41881Y275699D01*
G01X38780Y272598D02*
X41881Y269497D01*
G01X38780Y279291D02*
X41881Y282392D01*
G01X38780Y279291D02*
X41881Y276190D01*
G01X45679D02*
X48780Y279291D01*
G01D02*
X51881Y282392D01*
G01X45679D02*
X48780Y279291D01*
G01D02*
X51881Y276190D01*
G01X45679Y269497D02*
X48780Y272598D01*
G01D02*
X51881Y275699D01*
G01X45679D02*
X48780Y272598D01*
G01D02*
X51881Y269497D01*
G01X45679Y289497D02*
X48780Y292598D01*
G01D02*
X51881Y295699D01*
G01X45679D02*
X48780Y292598D01*
G01D02*
X51881Y289497D01*
G01X38780Y292598D02*
X41881Y295699D01*
G01X38780Y292598D02*
X41881Y289497D01*
G01X38780Y299291D02*
X41881Y302392D01*
G01X38780Y299291D02*
X41881Y296190D01*
G01X45679D02*
X48780Y299291D01*
G01D02*
X51881Y302392D01*
G01X45679D02*
X48780Y299291D01*
G01D02*
X51881Y296190D01*
X3005Y19808D03*
Y34808D03*
Y59808D03*
X7595Y128373D03*
X3005Y145238D03*
Y165238D03*
Y185238D03*
Y205238D03*
Y225238D03*
Y245238D03*
Y265238D03*
Y285238D03*
Y305238D03*
Y325238D03*
Y345238D03*
Y365238D03*
Y385238D03*
Y405238D03*
Y425238D03*
Y445238D03*
X3023Y524312D03*
Y549312D03*
X4540Y566003D03*
X34582Y3004D03*
X14811Y3732D03*
X12767Y72072D03*
X27271Y127298D03*
X19558Y454589D03*
X9913Y510026D03*
X20498Y575739D03*
X54582Y3004D03*
X39549Y454916D03*
X40498Y575739D03*
X60498D03*
X94582Y3004D03*
X74582D03*
X80498Y575739D03*
X114582Y3004D03*
X123000Y414500D03*
X119500D03*
Y411500D03*
X123000D03*
X119500Y408500D03*
X123000D03*
X119500Y417500D03*
X123000D03*
X119500Y420500D03*
X123000D03*
X115700Y420600D03*
Y417600D03*
Y408600D03*
Y411600D03*
Y414600D03*
X123000Y426600D03*
X119500D03*
X123000Y423600D03*
X119500D03*
X115700Y423700D03*
Y426700D03*
X100498Y575739D03*
X120498D03*
X154582Y3004D03*
X134582D03*
X154840Y244730D03*
X140400Y258360D03*
X143400D03*
X140400Y261360D03*
X143400D03*
X140400Y255360D03*
X143400D03*
X140498Y575739D03*
X174582Y3004D03*
X182260Y197050D03*
X179460D03*
X176560D03*
X174660Y205850D03*
Y202650D03*
X167660Y213050D03*
X164760D03*
X167660Y209850D03*
X164760D03*
X166068Y238749D03*
X161400Y323200D03*
X157000Y414500D03*
X160500D03*
Y417500D03*
X157000D03*
X160500Y420500D03*
X157000D03*
X160500Y411500D03*
X157000D03*
X160500Y408500D03*
X157000D03*
X164000Y414600D03*
Y417600D03*
Y420600D03*
Y411600D03*
Y408600D03*
X160300Y423600D03*
X156800D03*
X160300Y426600D03*
X156800D03*
X163800Y426700D03*
Y423700D03*
X168939Y498000D03*
X171939D03*
Y518000D03*
X168939D03*
X214582Y3004D03*
X194582D03*
X194160Y205200D03*
Y208200D03*
X200160Y205200D03*
Y208200D03*
X197160Y205200D03*
Y208200D03*
X185260Y205350D03*
Y208350D03*
X208071Y305975D03*
X234582Y3004D03*
X218500Y305000D03*
X226975D03*
X235975D03*
X239567Y305975D03*
X216939Y498000D03*
X219939D03*
Y518000D03*
X216939D03*
X254582Y3004D03*
X264939Y498000D03*
X267939D03*
Y518000D03*
X264939D03*
X294582Y3004D03*
X274582D03*
X283000Y203500D03*
Y198500D03*
Y196000D03*
Y206000D03*
X285219Y279078D03*
X281219D03*
X277219D03*
X285219Y275078D03*
X281219D03*
X277219D03*
X285219Y271078D03*
X281219D03*
X277219D03*
Y283078D03*
X281219D03*
X285219D03*
X314582Y3004D03*
X326000Y203500D03*
Y198500D03*
Y196000D03*
Y206000D03*
X304500Y203500D03*
Y198500D03*
Y196000D03*
Y206000D03*
X326419Y498000D03*
X329419D03*
Y518000D03*
X326419D03*
X354582Y3004D03*
X334582D03*
X347500Y203500D03*
Y198500D03*
Y196000D03*
Y206000D03*
X374582Y3004D03*
X390500Y203500D03*
Y198500D03*
Y196000D03*
Y206000D03*
X369000Y203500D03*
Y198500D03*
Y196000D03*
Y206000D03*
X375475Y305000D03*
X383975D03*
X365551Y305975D03*
X374419Y498000D03*
X377419D03*
Y518000D03*
X374419D03*
X414582Y3004D03*
X394582D03*
X412000Y203500D03*
Y198500D03*
Y196000D03*
Y206000D03*
X393000Y305000D03*
X397047Y305975D03*
X434582Y3004D03*
X422419Y498000D03*
X425419D03*
Y518000D03*
X422419D03*
X474582Y3004D03*
X454582D03*
X494582D03*
X483900Y498000D03*
X486900D03*
Y518000D03*
X483900D03*
X534582Y3004D03*
X514582D03*
X533475Y305500D03*
X523032Y305975D03*
X531900Y498000D03*
X534900D03*
Y518000D03*
X531900D03*
X554582Y3004D03*
X542475Y305500D03*
X551475D03*
X554528Y305975D03*
X562000Y442000D03*
X564500D03*
X594582Y3004D03*
X574582D03*
X590500Y203000D03*
Y198000D03*
Y195500D03*
Y205500D03*
X582900Y518000D03*
Y498000D03*
X579900D03*
Y518000D03*
X614582Y3004D03*
X612000Y203000D03*
Y198000D03*
Y195500D03*
Y205500D03*
X654582Y3004D03*
X634582D03*
X640900Y42300D03*
X660200Y56800D03*
X655300D03*
X652300D03*
X638200Y44000D03*
Y46500D03*
X641100Y48100D03*
X655000Y203000D03*
Y198000D03*
Y195500D03*
Y205500D03*
X633500Y203000D03*
Y198000D03*
Y195500D03*
Y205500D03*
X644381Y518000D03*
Y498000D03*
X641381D03*
Y518000D03*
X674582Y3004D03*
X684525Y32500D03*
Y36500D03*
X683600Y56800D03*
X679000D03*
X676000D03*
X686500D03*
X671100D03*
X668100D03*
X663200D03*
X676500Y195500D03*
Y198000D03*
Y203000D03*
Y205500D03*
X680513Y305975D03*
X714582Y3004D03*
X694582D03*
X699500Y34500D03*
X696900Y53300D03*
X694200D03*
X691400D03*
X689900Y56600D03*
X693000D03*
X696100Y56700D03*
X706000Y61975D03*
X697990Y195500D03*
Y198000D03*
Y203000D03*
Y205500D03*
X712009Y305975D03*
X708956Y305500D03*
X690956D03*
X700000D03*
X692381Y518000D03*
Y498000D03*
X689381D03*
Y518000D03*
X734582Y3004D03*
X719490Y195500D03*
Y198000D03*
Y203000D03*
Y205500D03*
X732100Y332400D03*
X740381Y518000D03*
Y498000D03*
X737381D03*
Y518000D03*
X774582Y3004D03*
X754582D03*
X761560Y38500D03*
X758760D03*
X756160D03*
X761560Y30000D03*
X758760D03*
X756160D03*
X758900Y27400D03*
X761560Y55500D03*
X758760D03*
X756160D03*
X761560Y47000D03*
X758760D03*
X756160D03*
X761560Y64000D03*
X758760D03*
X756160D03*
X794582Y3004D03*
X800575Y338000D03*
X803000Y357000D03*
Y346500D03*
X805323Y408150D03*
Y405150D03*
X799323D03*
Y408150D03*
X802323Y405150D03*
Y408150D03*
X796600Y408097D03*
Y405097D03*
X802323Y416916D03*
X799323D03*
X805323D03*
X802323Y413916D03*
X799323D03*
X805323D03*
Y411150D03*
X799323D03*
X802323D03*
X796600Y411097D03*
Y413863D03*
Y416863D03*
X799655Y474684D03*
Y480503D03*
Y477684D03*
X802655Y474684D03*
Y480503D03*
Y477684D03*
X805655Y474684D03*
Y480503D03*
Y477684D03*
X802655Y483503D03*
X805709Y486332D03*
X805655Y483503D03*
X796655Y474684D03*
Y480503D03*
Y477684D03*
X796709Y486332D03*
X796655Y483503D03*
X799709Y486332D03*
X799655Y483503D03*
X802709Y486332D03*
X834582Y3004D03*
X814582D03*
X811500Y329000D03*
X815500D03*
X823500D03*
X811323Y405150D03*
Y408150D03*
X808323D03*
Y405150D03*
Y416916D03*
X811323D03*
X808323Y413916D03*
X811323D03*
Y411150D03*
X808323D03*
X817153Y408096D03*
Y405096D03*
X814323Y405150D03*
Y408150D03*
Y416916D03*
X817153Y416862D03*
X814323Y413916D03*
X817153Y413862D03*
Y411096D03*
X814323Y411150D03*
X817709Y486332D03*
X817655Y483503D03*
X808655Y474684D03*
Y480503D03*
Y477684D03*
X811655Y474684D03*
Y480503D03*
Y477684D03*
X814655D03*
Y480503D03*
Y474684D03*
X808709Y486332D03*
X808655Y483503D03*
X811709Y486332D03*
X811655Y483503D03*
X814655D03*
X814709Y486332D03*
X817655Y474684D03*
Y480503D03*
Y477684D03*
X854582Y3004D03*
X849490Y196000D03*
Y198500D03*
Y203500D03*
Y206000D03*
X841000Y260525D03*
X846000D03*
X851000D03*
X856000D03*
X848075Y306500D03*
X839692Y329592D03*
X854825Y330925D03*
X849000Y399000D03*
X850390Y385878D03*
X847390D03*
X859253D03*
X856253D03*
X865542Y385771D03*
X859342Y413916D03*
X856342D03*
X865342D03*
X862342D03*
Y411150D03*
X865342D03*
X856342D03*
X859342D03*
X853619Y411097D03*
Y413863D03*
Y416863D03*
X862342Y408150D03*
Y405150D03*
X865342Y408150D03*
Y405150D03*
X856342D03*
Y408150D03*
X859342Y405150D03*
Y408150D03*
X853619Y408097D03*
Y405097D03*
X859342Y416916D03*
X856342D03*
X865342D03*
X862342D03*
X856257Y474684D03*
Y480503D03*
Y477684D03*
X859257Y474684D03*
Y480503D03*
Y477684D03*
X862257Y474684D03*
Y480503D03*
Y477684D03*
X859257Y483503D03*
X862311Y486332D03*
X862257Y483503D03*
X853257Y474684D03*
Y480503D03*
Y477684D03*
X853311Y486332D03*
X853257Y483503D03*
X856311Y486332D03*
X856257Y483503D03*
X859311Y486332D03*
X865311D03*
X865257Y483503D03*
Y474684D03*
Y480503D03*
Y477684D03*
X854082Y505410D03*
X848263D03*
X851082D03*
X854082Y508410D03*
X848263D03*
X851082D03*
X854082Y511410D03*
X848263D03*
X851082D03*
X854082Y514410D03*
X848263D03*
X851082D03*
X845263Y508410D03*
X842434Y511464D03*
X845263Y511410D03*
X842434Y514464D03*
X845263Y514410D03*
X854082Y502410D03*
X848263D03*
X851082D03*
X842434Y502464D03*
X845263Y502410D03*
X842434Y505464D03*
X845263Y505410D03*
X842434Y508464D03*
Y523464D03*
X845263Y523410D03*
X854082Y517410D03*
X848263D03*
X851082D03*
Y520410D03*
X848263D03*
X854082D03*
X842434Y517464D03*
X845263Y517410D03*
Y520410D03*
X842434Y520464D03*
X854082Y523410D03*
X848263D03*
X851082D03*
X894582Y3004D03*
X874582D03*
X870000Y304525D03*
X875000D03*
X880000D03*
X874000Y358475D03*
X885500Y352925D03*
X893091Y385771D03*
X874405D03*
X877405D03*
X868542D03*
X884228D03*
X887228D03*
X868342Y416916D03*
X871342D03*
X868342Y413916D03*
X871342D03*
Y411150D03*
X868342D03*
X874172Y408096D03*
Y405096D03*
Y416862D03*
Y413862D03*
Y411096D03*
X871342Y405150D03*
Y408150D03*
X868342Y405150D03*
Y408150D03*
X868311Y486332D03*
X868257Y483503D03*
Y477684D03*
Y480503D03*
Y474684D03*
X871311Y486332D03*
X874311D03*
X874257Y477684D03*
Y480503D03*
Y474684D03*
X871257Y483503D03*
Y474684D03*
Y480503D03*
Y477684D03*
X874257Y483503D03*
X914582Y3004D03*
X904500Y292000D03*
X915000Y322425D03*
X912000Y332425D03*
X920000Y355525D03*
X896091Y385771D03*
X912525Y385877D03*
X906662D03*
X903662D03*
X922454Y385771D03*
X915525Y385877D03*
X911776Y507184D03*
Y510184D03*
Y501184D03*
Y504184D03*
X923595Y498461D03*
X920595D03*
X920542Y504184D03*
X923542D03*
X920542Y501184D03*
X923542D03*
Y510184D03*
X920542D03*
X923542Y507184D03*
X920542D03*
Y513184D03*
X923542D03*
X911829Y498461D03*
X914829D03*
X917595D03*
X917542Y504184D03*
Y501184D03*
Y510184D03*
Y507184D03*
Y513184D03*
X914776D03*
Y507184D03*
Y510184D03*
Y501184D03*
Y504184D03*
X911776Y513184D03*
X920542Y516184D03*
X923542D03*
X917542D03*
X914776D03*
X911776D03*
X917596Y519014D03*
X914830D03*
X911830D03*
X923596D03*
X920596D03*
X934582Y3004D03*
X926000Y283475D03*
X937516Y300075D03*
X947000Y302475D03*
X930500Y315460D03*
X943172Y310885D03*
X927000Y357925D03*
X943885Y352385D03*
X925454Y385771D03*
X944247Y385877D03*
X941247D03*
X931317Y385771D03*
X934317D03*
X950110Y385877D03*
X953110D03*
X940498Y575739D03*
X974582Y3004D03*
X954582D03*
X960498Y575739D03*
X980498D03*
X994582Y3004D03*
X1000498Y575739D03*
X1034582Y3004D03*
X1014582D03*
X1019040Y157310D03*
X1019030Y160330D03*
X1039016Y185925D03*
X1020498Y575739D03*
X1040498D03*
X1054582Y3004D03*
X1070400Y123200D03*
X1067600D03*
X1068900Y110000D03*
X1060000Y249000D03*
X1063000D03*
X1066000D03*
Y246000D03*
X1063000D03*
X1060000D03*
X1066000Y243000D03*
X1063000D03*
X1060000D03*
X1069000Y246000D03*
Y243000D03*
X1072000Y246000D03*
Y243000D03*
X1060000Y252000D03*
X1063000D03*
X1066000D03*
Y258000D03*
X1063000D03*
X1060000D03*
X1066000Y255000D03*
X1063000D03*
X1060000D03*
X1069000Y258000D03*
Y255000D03*
X1072000Y258000D03*
Y255000D03*
X1060000Y296500D03*
X1063000D03*
X1066000D03*
Y293500D03*
X1063000D03*
X1060000D03*
X1069000D03*
X1060000Y299500D03*
X1063000D03*
X1066000D03*
Y305500D03*
X1063000D03*
X1060000D03*
X1066000Y302500D03*
X1063000D03*
X1060000D03*
X1069000Y305500D03*
Y302500D03*
X1066000Y290500D03*
X1063000D03*
X1060000D03*
X1069000D03*
X1072000Y293500D03*
Y305500D03*
Y302500D03*
Y290500D03*
X1066000Y338000D03*
X1063000D03*
X1060000D03*
X1069000D03*
X1072000D03*
X1060000Y344000D03*
X1063000D03*
X1066000D03*
X1060000Y347000D03*
X1063000D03*
X1066000D03*
Y341000D03*
X1063000D03*
X1060000D03*
X1066000Y353000D03*
X1063000D03*
X1060000D03*
X1066000Y350000D03*
X1063000D03*
X1060000D03*
X1069000Y353000D03*
Y350000D03*
Y341000D03*
X1072000Y353000D03*
Y350000D03*
Y341000D03*
X1066000Y397500D03*
X1063000D03*
X1060000D03*
X1069000D03*
X1060000Y391500D03*
X1063000D03*
X1066000D03*
X1060000Y394500D03*
X1063000D03*
X1066000D03*
Y388500D03*
X1063000D03*
X1060000D03*
X1066000Y385500D03*
X1063000D03*
X1060000D03*
X1069000Y388500D03*
Y385500D03*
X1072000Y397500D03*
Y388500D03*
Y385500D03*
X1066000Y400500D03*
X1063000D03*
X1060000D03*
X1069000D03*
X1072000D03*
X1066000Y433000D03*
X1063000D03*
X1060000D03*
X1069000D03*
X1060000Y439000D03*
X1063000D03*
X1066000D03*
X1060000Y442000D03*
X1063000D03*
X1066000D03*
Y436000D03*
X1063000D03*
X1060000D03*
X1069000D03*
X1072000Y433000D03*
Y436000D03*
X1066000Y448000D03*
X1063000D03*
X1060000D03*
X1066000Y445000D03*
X1063000D03*
X1060000D03*
X1069000Y448000D03*
Y445000D03*
X1072000Y448000D03*
Y445000D03*
X1069000Y480500D03*
Y483500D03*
X1060000Y480500D03*
X1063000D03*
X1066000D03*
X1060000Y483500D03*
X1063000D03*
X1066000D03*
Y486500D03*
X1063000D03*
X1060000D03*
X1072000Y480500D03*
Y483500D03*
X1069000Y492500D03*
Y495500D03*
X1060000Y492500D03*
X1063000D03*
X1066000D03*
X1060000Y495500D03*
X1063000D03*
X1066000D03*
Y489500D03*
X1063000D03*
X1060000D03*
X1072000Y492500D03*
Y495500D03*
X1066500Y538000D03*
Y541000D03*
X1069500D03*
X1066500Y544000D03*
X1069500D03*
Y538000D03*
X1060498Y575739D03*
X1069500Y547000D03*
Y550000D03*
X1066500Y547000D03*
Y550000D03*
Y553000D03*
X1069500D03*
X1094582Y3004D03*
X1074582D03*
X1097100Y35582D03*
Y38582D03*
X1099600D03*
Y35582D03*
X1102100D03*
Y38582D03*
X1096961Y18126D03*
Y21126D03*
X1099461D03*
Y18126D03*
X1101961D03*
Y21126D03*
X1097101Y53737D03*
Y56737D03*
X1099601D03*
Y53737D03*
X1102101D03*
Y56737D03*
X1091000Y99500D03*
X1095100D03*
X1073200Y126000D03*
Y128800D03*
Y123200D03*
X1084740Y108000D03*
X1084325Y130197D03*
X1101903Y285019D03*
X1101796Y331894D03*
X1080498Y575739D03*
X1100498D03*
X1114582Y3004D03*
X1125170Y35582D03*
Y38582D03*
X1127670D03*
Y35582D03*
X1130170D03*
Y38582D03*
X1104600Y35582D03*
Y38582D03*
X1107100Y35582D03*
Y38582D03*
X1104461Y18126D03*
Y21126D03*
X1106961Y18126D03*
Y21126D03*
X1130031D03*
Y18126D03*
X1127531D03*
Y21126D03*
X1125031D03*
Y18126D03*
X1104601Y53737D03*
Y56737D03*
X1107101Y53737D03*
Y56737D03*
X1113000Y101240D03*
X1119500Y86000D03*
Y83000D03*
X1115800Y126600D03*
X1125918Y195418D03*
X1129068Y195500D03*
X1117206Y231741D03*
X1117290Y224241D03*
X1106106Y231741D03*
X1118774Y284699D03*
X1112902D03*
X1110019Y284806D03*
X1104786Y284912D03*
X1121657Y284592D03*
X1118667Y331574D03*
X1112795D03*
X1109912Y331681D03*
X1104679Y331787D03*
X1121550Y331467D03*
X1104009Y427245D03*
X1120880Y426925D03*
X1115008D03*
X1112125Y427032D03*
X1106892Y427138D03*
X1123763Y426818D03*
X1103800Y474339D03*
X1106683Y474232D03*
X1111916Y474126D03*
X1114799Y474019D03*
X1120671D03*
X1123554Y473912D03*
X1111452Y544000D03*
Y541000D03*
X1114452Y544000D03*
Y541000D03*
Y538000D03*
X1111452D03*
X1120669Y544000D03*
Y541000D03*
X1123669Y544000D03*
Y541000D03*
Y538000D03*
X1120669D03*
X1120498Y575739D03*
X1114452Y553000D03*
X1111452D03*
X1114452Y550000D03*
X1111452D03*
X1114452Y547000D03*
X1111452D03*
X1123669Y553000D03*
X1120669D03*
X1123669Y550000D03*
X1120669D03*
X1123669Y547000D03*
X1120669D03*
X1154582Y3004D03*
X1134582D03*
X1132670Y35582D03*
X1135170D03*
Y38582D03*
X1132670D03*
X1135031Y21126D03*
Y18126D03*
X1132531Y21126D03*
Y18126D03*
X1132950Y82867D03*
Y85867D03*
X1135450D03*
Y82867D03*
X1137950D03*
X1140450D03*
X1142950D03*
Y85867D03*
X1140450D03*
X1137950D03*
X1155000Y124913D03*
X1159300Y129700D03*
X1141500Y120500D03*
X1140336Y183560D03*
X1143490D03*
X1158000Y179000D03*
X1138203Y266860D03*
Y260860D03*
Y263860D03*
X1135203Y260860D03*
Y263860D03*
Y266860D03*
X1138203Y257860D03*
Y254860D03*
X1135203Y257860D03*
Y254860D03*
X1159710Y306037D03*
X1156710D03*
X1159710Y303037D03*
X1156710D03*
X1159710Y300037D03*
X1156710D03*
X1159710Y297037D03*
X1156710D03*
Y294037D03*
X1159710D03*
Y309037D03*
X1156710D03*
X1135403Y302360D03*
Y305360D03*
X1138403Y302360D03*
Y305360D03*
X1135403Y308360D03*
X1138403D03*
X1159710Y312037D03*
X1156710D03*
X1159710Y321037D03*
X1156710D03*
X1159710Y318037D03*
X1156710D03*
X1159710Y315037D03*
X1156710D03*
X1135403Y314360D03*
Y311360D03*
X1138403D03*
Y314360D03*
Y361979D03*
X1135403D03*
X1138403Y358979D03*
X1135403D03*
X1138403Y355979D03*
X1135403D03*
X1138403Y352979D03*
X1135403D03*
X1138403Y349979D03*
X1135403D03*
X1135190Y396965D03*
X1138190D03*
X1135190Y399965D03*
X1138190D03*
X1135190Y402965D03*
Y405965D03*
Y408965D03*
X1138190Y402965D03*
Y405965D03*
Y408965D03*
X1159799Y448537D03*
X1156799D03*
X1159799Y445537D03*
X1156799D03*
X1159799Y442537D03*
X1156799D03*
X1159799Y439537D03*
X1156799D03*
Y436537D03*
X1159799D03*
Y454537D03*
X1156799D03*
X1159799Y451537D03*
X1156799D03*
X1135404Y457228D03*
Y454228D03*
Y451228D03*
Y445228D03*
Y448228D03*
X1138404Y454228D03*
Y451228D03*
Y445228D03*
Y448228D03*
Y457228D03*
X1159799Y457537D03*
X1156799D03*
X1159799Y463537D03*
X1156799D03*
X1159799Y460537D03*
X1156799D03*
X1135622Y485732D03*
Y470732D03*
Y467732D03*
Y479732D03*
Y476732D03*
Y473732D03*
Y482732D03*
X1138622D03*
Y473732D03*
Y476732D03*
Y479732D03*
Y470732D03*
Y485732D03*
Y467732D03*
X1140498Y575739D03*
X1160498D03*
X1174582Y3004D03*
X1183321Y123652D03*
X1185821D03*
X1188321D03*
Y120652D03*
X1185821D03*
X1183321D03*
X1180821D03*
Y123652D03*
X1178321D03*
Y120652D03*
X1177475Y111500D03*
X1179500Y105500D03*
X1167600Y184500D03*
Y180500D03*
X1162710Y306037D03*
Y303037D03*
Y300037D03*
Y297037D03*
Y294037D03*
Y309037D03*
X1179411Y334250D03*
Y337750D03*
X1162710Y312037D03*
Y321037D03*
Y318037D03*
Y315037D03*
X1179411Y330750D03*
Y327250D03*
X1162799Y448537D03*
Y445537D03*
Y442537D03*
Y439537D03*
Y436537D03*
Y454537D03*
Y451537D03*
Y457537D03*
X1179500Y476750D03*
Y480250D03*
X1162799Y463537D03*
Y460537D03*
X1179500Y469750D03*
Y473250D03*
X1181075Y491734D03*
X1177925D03*
X1180498Y575739D03*
X1214582Y3004D03*
X1194582D03*
X1203887Y306894D03*
X1200887D03*
X1197887D03*
X1203887Y303894D03*
X1200887D03*
X1197887D03*
X1203887Y300894D03*
X1200887D03*
X1197887D03*
X1203887Y297894D03*
X1200887D03*
X1197887D03*
X1203887Y294894D03*
X1200887D03*
X1197887D03*
Y321894D03*
X1200887D03*
X1203887D03*
Y318894D03*
X1200887D03*
X1197887D03*
X1203887Y315894D03*
X1200887D03*
X1197887D03*
X1203887Y312894D03*
X1200887D03*
X1197887D03*
X1203887Y309894D03*
X1200887D03*
X1197887D03*
X1197976Y437394D03*
X1200976D03*
X1203976D03*
X1197976Y440394D03*
X1200976D03*
X1203976D03*
X1197976Y443394D03*
X1200976D03*
X1203976D03*
X1197976Y446394D03*
X1200976D03*
X1203976D03*
X1197976Y449394D03*
X1200976D03*
X1203976D03*
X1197976Y452394D03*
X1200976D03*
X1203976D03*
X1197976Y455394D03*
X1200976D03*
X1203976D03*
X1197976Y464394D03*
X1200976D03*
X1203976D03*
X1197976Y458394D03*
X1200976D03*
X1203976D03*
X1197976Y461394D03*
X1200976D03*
X1203976D03*
X1200498Y575739D03*
X1220498D03*
X1234582Y3004D03*
X1240498Y575739D03*
X1277657Y4128D03*
X1254582Y3004D03*
X1260498Y575739D03*
X1279438Y573806D03*
X1286766Y12634D03*
X1288331Y30962D03*
Y70962D03*
Y50962D03*
Y90962D03*
Y130962D03*
Y110962D03*
Y150962D03*
Y190962D03*
Y170962D03*
Y210962D03*
Y230962D03*
Y270962D03*
Y250962D03*
Y290962D03*
Y330962D03*
Y310962D03*
Y350962D03*
Y390962D03*
Y370962D03*
Y410962D03*
Y450962D03*
Y430962D03*
Y470962D03*
Y510962D03*
Y490962D03*
Y530962D03*
X1287616Y563889D03*
X1288331Y550962D03*
G54D11*
X38780Y232598D03*
Y239291D03*
Y252598D03*
Y259291D03*
Y272598D03*
Y279291D03*
Y292598D03*
Y299291D03*
X48780Y232598D03*
Y239291D03*
Y252598D03*
Y259291D03*
Y272598D03*
Y279291D03*
Y292598D03*
Y299291D03*
G54D20*
X1011000Y108000D03*
G54D21*
X1240158Y57480D03*
Y521260D03*
G54D12*
X165350Y220098D03*
X162850D03*
Y227185D03*
Y230728D03*
X165350Y223642D03*
Y227185D03*
Y230728D03*
X162850Y223642D03*
G54D22*
G01X1026330Y157890D02*
X1026031D01*
X1025738Y158183D01*
X1019913D01*
X1019040Y157310D01*
G01X1026330Y159890D02*
X1026123Y159683D01*
X1019677D01*
X1019030Y160330D01*
G01X1106106Y231741D02*
X1077741D01*
X1042100Y196100D01*
Y189009D01*
X1039016Y185925D01*
G01X1125918Y195418D02*
X1126780Y196280D01*
Y204998D01*
X1111700Y220078D01*
Y226837D01*
X1113576Y228713D01*
X1114825D01*
X1116241Y228729D01*
X1117230Y229740D01*
X1117206Y231741D01*
G01X1129068Y195500D02*
X1128280Y196288D01*
Y205620D01*
X1113200Y220700D01*
Y226213D01*
X1114200Y227213D01*
X1114842D01*
X1116255Y227229D01*
X1117266Y226242D01*
X1117290Y224241D01*
G54D13*
X178819Y277204D03*
X193819D03*
X253819D03*
X268819D03*
X336299D03*
X351299D03*
X493780D03*
X508780D03*
X651261D03*
X666261D03*
G54D23*
G01X927000Y357925D02*
Y355000D01*
G01X1181075Y491734D02*
X1180530Y491189D01*
Y488178D01*
X1171220Y478868D01*
Y239620D01*
X1166648Y235048D01*
X1066698D01*
X1031620Y199970D01*
Y161520D01*
X1027990Y157890D01*
X1026330D01*
G01X1177925Y491734D02*
X1178530Y491129D01*
Y489007D01*
X1169220Y479697D01*
Y240449D01*
X1165819Y237048D01*
X1065869D01*
X1029620Y200799D01*
Y162349D01*
X1027161Y159890D01*
X1026330D01*
G01X1179411Y330750D02*
X1178661Y330000D01*
X1178231D01*
X1174989Y326758D01*
Y232088D01*
X1140940Y198039D01*
Y184164D01*
X1140336Y183560D01*
G01X1179411Y327250D02*
X1178489D01*
X1176989Y325750D01*
Y231259D01*
X1142940Y197210D01*
Y184110D01*
X1143490Y183560D01*
G01X1179500Y476750D02*
X1177790D01*
X1176290Y475250D01*
Y467740D01*
X1186694Y457336D01*
Y337644D01*
X1184020Y334970D01*
X1180131D01*
X1179411Y334250D01*
G01X1179500Y480250D02*
X1178000Y478750D01*
X1176961D01*
X1174290Y476079D01*
Y466911D01*
X1184694Y456507D01*
Y338473D01*
X1183191Y336970D01*
X1180191D01*
X1179411Y337750D01*
G01X1179500Y469750D02*
X1179805Y470055D01*
X1181927D01*
X1189830Y462152D01*
Y336345D01*
X1186237Y332752D01*
Y331517D01*
X1184700Y329980D01*
X1180181D01*
X1179411Y330750D01*
G01X1179500Y473250D02*
X1179690D01*
X1180885Y472055D01*
X1182756D01*
X1191830Y462981D01*
Y335516D01*
X1188237Y331923D01*
Y330688D01*
X1185529Y327980D01*
X1180141D01*
X1179411Y327250D01*
G54D14*
X165539Y539000D03*
X213539D03*
X261539D03*
X323019D03*
X371019D03*
X419019D03*
X480500D03*
X528500D03*
X576500D03*
X637981D03*
X685981D03*
X733981D03*
G54D24*
G01X162651Y536112D02*
X165539Y539000D01*
G01D02*
X168427Y541888D01*
G01X162651D02*
X165539Y539000D01*
G01D02*
X168427Y536112D01*
G01X210651D02*
X213539Y539000D01*
G01D02*
X216427Y541888D01*
G01X210651D02*
X213539Y539000D01*
G01D02*
X216427Y536112D01*
G01X268000Y240000D02*
X270818Y237182D01*
G01X265182Y242818D02*
X268000Y240000D01*
G01D02*
X270818Y242818D01*
G01X265182Y237182D02*
X268000Y240000D01*
G01X258651Y536112D02*
X261539Y539000D01*
G01D02*
X264427Y541888D01*
G01X258651D02*
X261539Y539000D01*
G01D02*
X264427Y536112D01*
G01X312500Y240000D02*
X315318Y237182D01*
G01X309682Y242818D02*
X312500Y240000D01*
G01D02*
X315318Y242818D01*
G01X309682Y237182D02*
X312500Y240000D01*
G01X320131Y536112D02*
X323019Y539000D01*
G01D02*
X325907Y541888D01*
G01X320131D02*
X323019Y539000D01*
G01D02*
X325907Y536112D01*
G01X357000Y240000D02*
X359818Y237182D01*
G01X354182Y242818D02*
X357000Y240000D01*
G01D02*
X359818Y242818D01*
G01X354182Y237182D02*
X357000Y240000D01*
G01X368131Y536112D02*
X371019Y539000D01*
G01D02*
X373907Y541888D01*
G01X368131D02*
X371019Y539000D01*
G01D02*
X373907Y536112D01*
G01X416131D02*
X419019Y539000D01*
G01D02*
X421907Y541888D01*
G01X416131D02*
X419019Y539000D01*
G01D02*
X421907Y536112D01*
G01X428500Y240000D02*
X431318Y237182D01*
G01X425682Y242818D02*
X428500Y240000D01*
G01D02*
X431318Y242818D01*
G01X425682Y237182D02*
X428500Y240000D01*
G01X472500D02*
X475318Y237182D01*
G01X469682Y242818D02*
X472500Y240000D01*
G01D02*
X475318Y242818D01*
G01X469682Y237182D02*
X472500Y240000D01*
G01X477612Y536112D02*
X480500Y539000D01*
G01D02*
X483388Y541888D01*
G01X477612D02*
X480500Y539000D01*
G01D02*
X483388Y536112D01*
G01X516500Y240000D02*
X519318Y237182D01*
G01X513682Y242818D02*
X516500Y240000D01*
G01D02*
X519318Y242818D01*
G01X513682Y237182D02*
X516500Y240000D01*
G01X525612Y536112D02*
X528500Y539000D01*
G01D02*
X531388Y541888D01*
G01X525612D02*
X528500Y539000D01*
G01D02*
X531388Y536112D01*
G01X578500Y240000D02*
X581318Y237182D01*
G01X575682Y242818D02*
X578500Y240000D01*
G01D02*
X581318Y242818D01*
G01X575682Y237182D02*
X578500Y240000D01*
G01X573612Y536112D02*
X576500Y539000D01*
G01D02*
X579388Y541888D01*
G01X573612D02*
X576500Y539000D01*
G01D02*
X579388Y536112D01*
G01X622500Y240000D02*
X625318Y237182D01*
G01X619682Y242818D02*
X622500Y240000D01*
G01D02*
X625318Y242818D01*
G01X619682Y237182D02*
X622500Y240000D01*
G01X635093Y536112D02*
X637981Y539000D01*
G01D02*
X640869Y541888D01*
G01X635093D02*
X637981Y539000D01*
G01D02*
X640869Y536112D01*
G01X666500Y240000D02*
X669318Y237182D01*
G01X663682Y242818D02*
X666500Y240000D01*
G01D02*
X669318Y242818D01*
G01X663682Y237182D02*
X666500Y240000D01*
G01X683093Y536112D02*
X685981Y539000D01*
G01D02*
X688869Y541888D01*
G01X683093D02*
X685981Y539000D01*
G01D02*
X688869Y536112D01*
G01X735981Y240000D02*
X738799Y237182D01*
G01X733163Y242818D02*
X735981Y240000D01*
G01D02*
X738799Y242818D01*
G01X733163Y237182D02*
X735981Y240000D01*
G01X731093Y536112D02*
X733981Y539000D01*
G01D02*
X736869Y541888D01*
G01X731093D02*
X733981Y539000D01*
G01D02*
X736869Y536112D01*
G01X777163Y242818D02*
X779981Y240000D01*
G01X777163Y237182D02*
X779981Y240000D01*
G01D02*
X782799Y237182D01*
G01X779981Y240000D02*
X782799Y242818D01*
G01X821163Y237182D02*
X823981Y240000D01*
G01D02*
X826799Y242818D01*
G01X821163D02*
X823981Y240000D01*
G01D02*
X826799Y237182D01*
G54D15*
X268000Y240000D03*
X312500D03*
X357000D03*
X428500D03*
X472500D03*
X516500D03*
X578500D03*
X622500D03*
X666500D03*
X735981D03*
X779981D03*
X823981D03*
G54D25*
G01X173774Y272159D02*
X178819Y277204D01*
G01D02*
X183864Y282249D01*
G01X173774D02*
X178819Y277204D01*
G01D02*
X183864Y272159D01*
G01X188774D02*
X193819Y277204D01*
G01D02*
X198864Y282249D01*
G01X188774D02*
X193819Y277204D01*
G01X263774Y272159D02*
X268819Y277204D01*
G01D02*
X273864Y282249D01*
G01X263774D02*
X268819Y277204D01*
G01D02*
X273864Y272159D01*
G01X248774D02*
X253819Y277204D01*
G01D02*
X258864Y282249D01*
G01X248774D02*
X253819Y277204D01*
G01D02*
X258864Y272159D01*
G01X249835Y473220D02*
X253819Y477204D01*
G01D02*
X257803Y481188D01*
G01X249835D02*
X253819Y477204D01*
G01D02*
X257803Y473220D01*
G01X336299Y277204D02*
X331254Y272159D01*
G01Y282249D02*
X336299Y277204D01*
G01D02*
X341344Y282249D01*
G01X351299Y277204D02*
X356344Y282249D01*
G01X346254D02*
X351299Y277204D01*
G01D02*
X356344Y272159D01*
G01X336299Y277204D02*
X341344Y272159D01*
G01X351299Y277204D02*
X346254Y272159D01*
G01X407315Y473220D02*
X411299Y477204D01*
G01D02*
X415283Y481188D01*
G01X407315D02*
X411299Y477204D01*
G01D02*
X415283Y473220D01*
G01X488735Y272159D02*
X493780Y277204D01*
G01D02*
X498825Y282249D01*
G01X488735D02*
X493780Y277204D01*
G01D02*
X498825Y272159D01*
G01X503735D02*
X508780Y277204D01*
G01D02*
X513825Y282249D01*
G01X503735D02*
X508780Y277204D01*
G01D02*
X513825Y272159D01*
G01X564796Y473220D02*
X568780Y477204D01*
G01D02*
X572764Y481188D01*
G01X564796D02*
X568780Y477204D01*
G01D02*
X572764Y473220D01*
G01X646216Y272159D02*
X651261Y277204D01*
G01D02*
X656306Y282249D01*
G01X646216D02*
X651261Y277204D01*
G01D02*
X656306Y272159D01*
G01X661216D02*
X666261Y277204D01*
G01D02*
X671306Y282249D01*
G01X661216D02*
X666261Y277204D01*
G01D02*
X671306Y272159D01*
G01X722277Y473220D02*
X726261Y477204D01*
G01D02*
X730245Y481188D01*
G01X722277D02*
X726261Y477204D01*
G01D02*
X730245Y473220D01*
G54D16*
X253819Y477204D03*
X411299D03*
X568780D03*
X726261D03*
G54D26*
G01X-297025Y-1013390D02*
Y1828909D01*
X3691357D01*
Y-1013390D01*
X-297025D01*
G01X4093Y-769672D02*
Y-844672D01*
X504093D01*
Y-769672D01*
X4093D01*
G01X16093Y-834672D02*
Y-839672D01*
G01X14636Y-834672D02*
X17550D01*
G01X22460Y-839672D02*
X19926D01*
Y-834672D01*
X22460D01*
G01X21446Y-837089D02*
X19926D01*
G01X25026Y-834672D02*
Y-839672D01*
X27560D01*
G01X31393Y-839839D02*
X31266Y-839755D01*
Y-839589D01*
X31393Y-839505D01*
X31520Y-839589D01*
Y-839755D01*
X31393Y-839839D01*
G01Y-837589D02*
X31266Y-837505D01*
Y-837339D01*
X31393Y-837255D01*
X31520Y-837339D01*
Y-837505D01*
X31393Y-837589D01*
G01X36176Y-841339D02*
X35543Y-840505D01*
X35226Y-839672D01*
Y-836339D01*
X35543Y-835505D01*
X36176Y-834672D01*
G01X41593D02*
X41086Y-834839D01*
X40706Y-835255D01*
X40453Y-835755D01*
X40263Y-836422D01*
X40200Y-837172D01*
X40263Y-837922D01*
X40453Y-838589D01*
X40706Y-839089D01*
X41086Y-839505D01*
X41593Y-839672D01*
X42100Y-839505D01*
X42480Y-839089D01*
X42733Y-838589D01*
X42923Y-837922D01*
X42986Y-837172D01*
X42923Y-836422D01*
X42733Y-835755D01*
X42480Y-835255D01*
X42100Y-834839D01*
X41593Y-834672D01*
G01X45300Y-838672D02*
X45680Y-839255D01*
X46186Y-839589D01*
X46756Y-839672D01*
X47263Y-839589D01*
X47770Y-839172D01*
X48086Y-838672D01*
X48150Y-838172D01*
X48023Y-837589D01*
X47580Y-837172D01*
X47136Y-837005D01*
X46566D01*
G01X47136D02*
X47516Y-836755D01*
X47833Y-836339D01*
X47960Y-835839D01*
X47833Y-835339D01*
X47516Y-834922D01*
X46946Y-834672D01*
X46376Y-834755D01*
X45806Y-835089D01*
G01X52110Y-841339D02*
X52743Y-840505D01*
X53060Y-839672D01*
Y-836339D01*
X52743Y-835505D01*
X52110Y-834672D01*
G01X55500Y-838672D02*
X55880Y-839255D01*
X56386Y-839589D01*
X56956Y-839672D01*
X57463Y-839589D01*
X57970Y-839172D01*
X58286Y-838672D01*
X58350Y-838172D01*
X58223Y-837589D01*
X57780Y-837172D01*
X57336Y-837005D01*
X56766D01*
G01X57336D02*
X57716Y-836755D01*
X58033Y-836339D01*
X58160Y-835839D01*
X58033Y-835339D01*
X57716Y-834922D01*
X57146Y-834672D01*
X56576Y-834755D01*
X56006Y-835089D01*
G01X60790Y-835505D02*
X61170Y-835005D01*
X61613Y-834755D01*
X62120Y-834672D01*
X62753Y-834839D01*
X63196Y-835255D01*
X63323Y-835755D01*
X63260Y-836255D01*
X63006Y-836672D01*
X61740Y-837505D01*
X61170Y-838089D01*
X60790Y-838922D01*
X60663Y-839672D01*
X63323D01*
G01X66966D02*
X67093Y-838589D01*
X67283Y-837672D01*
X67536Y-836839D01*
X67853Y-835922D01*
X68360Y-834672D01*
X65826D01*
G01X71370Y-838005D02*
X73016D01*
G01X76090Y-835505D02*
X76470Y-835005D01*
X76913Y-834755D01*
X77420Y-834672D01*
X78053Y-834839D01*
X78496Y-835255D01*
X78623Y-835755D01*
X78560Y-836255D01*
X78306Y-836672D01*
X77040Y-837505D01*
X76470Y-838089D01*
X76090Y-838922D01*
X75963Y-839672D01*
X78623D01*
G01X81000Y-838672D02*
X81380Y-839255D01*
X81886Y-839589D01*
X82456Y-839672D01*
X82963Y-839589D01*
X83470Y-839172D01*
X83786Y-838672D01*
X83850Y-838172D01*
X83723Y-837589D01*
X83280Y-837172D01*
X82836Y-837005D01*
X82266D01*
G01X82836D02*
X83216Y-836755D01*
X83533Y-836339D01*
X83660Y-835839D01*
X83533Y-835339D01*
X83216Y-834922D01*
X82646Y-834672D01*
X82076Y-834755D01*
X81506Y-835089D01*
G01X88253Y-839672D02*
Y-834672D01*
X85910Y-838255D01*
X89076D01*
G01X91200Y-838922D02*
X91580Y-839339D01*
X92023Y-839589D01*
X92593Y-839672D01*
X93163Y-839505D01*
X93606Y-839172D01*
X93923Y-838589D01*
X93986Y-837922D01*
X93860Y-837255D01*
X93543Y-836839D01*
X93100Y-836505D01*
X92656Y-836422D01*
X92213Y-836505D01*
X91643Y-836839D01*
X91833Y-834672D01*
X93543D01*
G01X101590Y-839672D02*
Y-834672D01*
X103996D01*
G01X103110Y-837089D02*
X101590D01*
G01X106310Y-839672D02*
X107893Y-834672D01*
X109476Y-839672D01*
G01X108906Y-837922D02*
X106880D01*
G01X111663Y-839672D02*
X114323Y-834672D01*
G01X111663D02*
X114323Y-839672D01*
G01X118093Y-839839D02*
X117966Y-839755D01*
Y-839589D01*
X118093Y-839505D01*
X118220Y-839589D01*
Y-839755D01*
X118093Y-839839D01*
G01Y-837589D02*
X117966Y-837505D01*
Y-837339D01*
X118093Y-837255D01*
X118220Y-837339D01*
Y-837505D01*
X118093Y-837589D01*
G01X122876Y-841339D02*
X122243Y-840505D01*
X121926Y-839672D01*
Y-836339D01*
X122243Y-835505D01*
X122876Y-834672D01*
G01X128293D02*
X127786Y-834839D01*
X127406Y-835255D01*
X127153Y-835755D01*
X126963Y-836422D01*
X126900Y-837172D01*
X126963Y-837922D01*
X127153Y-838589D01*
X127406Y-839089D01*
X127786Y-839505D01*
X128293Y-839672D01*
X128800Y-839505D01*
X129180Y-839089D01*
X129433Y-838589D01*
X129623Y-837922D01*
X129686Y-837172D01*
X129623Y-836422D01*
X129433Y-835755D01*
X129180Y-835255D01*
X128800Y-834839D01*
X128293Y-834672D01*
G01X132000Y-838672D02*
X132380Y-839255D01*
X132886Y-839589D01*
X133456Y-839672D01*
X133963Y-839589D01*
X134470Y-839172D01*
X134786Y-838672D01*
X134850Y-838172D01*
X134723Y-837589D01*
X134280Y-837172D01*
X133836Y-837005D01*
X133266D01*
G01X133836D02*
X134216Y-836755D01*
X134533Y-836339D01*
X134660Y-835839D01*
X134533Y-835339D01*
X134216Y-834922D01*
X133646Y-834672D01*
X133076Y-834755D01*
X132506Y-835089D01*
G01X138810Y-841339D02*
X139443Y-840505D01*
X139760Y-839672D01*
Y-836339D01*
X139443Y-835505D01*
X138810Y-834672D01*
G01X142200Y-838672D02*
X142580Y-839255D01*
X143086Y-839589D01*
X143656Y-839672D01*
X144163Y-839589D01*
X144670Y-839172D01*
X144986Y-838672D01*
X145050Y-838172D01*
X144923Y-837589D01*
X144480Y-837172D01*
X144036Y-837005D01*
X143466D01*
G01X144036D02*
X144416Y-836755D01*
X144733Y-836339D01*
X144860Y-835839D01*
X144733Y-835339D01*
X144416Y-834922D01*
X143846Y-834672D01*
X143276Y-834755D01*
X142706Y-835089D01*
G01X147616Y-839089D02*
X148060Y-839505D01*
X148566Y-839672D01*
X149073Y-839505D01*
X149516Y-839005D01*
X149833Y-838255D01*
X149960Y-837505D01*
Y-836589D01*
X149833Y-835839D01*
X149516Y-835172D01*
X149136Y-834839D01*
X148693Y-834672D01*
X148186Y-834839D01*
X147806Y-835172D01*
X147553Y-835672D01*
X147426Y-836339D01*
X147553Y-836922D01*
X147870Y-837505D01*
X148250Y-837839D01*
X148693Y-837922D01*
X149200Y-837755D01*
X149580Y-837339D01*
X149960Y-836589D01*
G01X153666Y-839672D02*
X153793Y-838589D01*
X153983Y-837672D01*
X154236Y-836839D01*
X154553Y-835922D01*
X155060Y-834672D01*
X152526D01*
G01X158070Y-838005D02*
X159716D01*
G01X162600Y-838672D02*
X162980Y-839255D01*
X163486Y-839589D01*
X164056Y-839672D01*
X164563Y-839589D01*
X165070Y-839172D01*
X165386Y-838672D01*
X165450Y-838172D01*
X165323Y-837589D01*
X164880Y-837172D01*
X164436Y-837005D01*
X163866D01*
G01X164436D02*
X164816Y-836755D01*
X165133Y-836339D01*
X165260Y-835839D01*
X165133Y-835339D01*
X164816Y-834922D01*
X164246Y-834672D01*
X163676Y-834755D01*
X163106Y-835089D01*
G01X167890Y-837589D02*
X168333Y-837005D01*
X168713Y-836672D01*
X169220Y-836505D01*
X169663Y-836672D01*
X169980Y-837005D01*
X170233Y-837505D01*
X170296Y-838089D01*
X170233Y-838589D01*
X169980Y-839089D01*
X169600Y-839505D01*
X169156Y-839672D01*
X168650Y-839505D01*
X168206Y-839005D01*
X167953Y-838255D01*
X167890Y-837422D01*
X168016Y-836339D01*
X168206Y-835755D01*
X168523Y-835172D01*
X168966Y-834755D01*
X169410Y-834672D01*
X169853Y-834839D01*
X170170Y-835255D01*
G01X174193Y-839672D02*
Y-834672D01*
X173433Y-835672D01*
G01Y-839672D02*
X174953D01*
G01X180053D02*
Y-834672D01*
X177710Y-838255D01*
X180876D01*
G01X199093Y-769672D02*
Y-844672D01*
G01Y-819672D02*
X302093D01*
Y-794672D01*
G01X199093D02*
X302093D01*
G01X309600Y-829672D02*
Y-824672D01*
X310866D01*
X311373Y-824922D01*
X311753Y-825255D01*
X312070Y-825755D01*
X312323Y-826339D01*
X312386Y-827172D01*
X312323Y-828005D01*
X312070Y-828589D01*
X311753Y-829089D01*
X311373Y-829422D01*
X310866Y-829672D01*
X309600D01*
G01X314510D02*
X316093Y-824672D01*
X317676Y-829672D01*
G01X317106Y-827922D02*
X315080D01*
G01X321193Y-824672D02*
Y-829672D01*
G01X319736Y-824672D02*
X322650D01*
G01X327560Y-829672D02*
X325026D01*
Y-824672D01*
X327560D01*
G01X326546Y-827089D02*
X325026D01*
G01X331393Y-829839D02*
X331266Y-829755D01*
Y-829589D01*
X331393Y-829505D01*
X331520Y-829589D01*
Y-829755D01*
X331393Y-829839D01*
G01Y-827589D02*
X331266Y-827505D01*
Y-827339D01*
X331393Y-827255D01*
X331520Y-827339D01*
Y-827505D01*
X331393Y-827589D01*
G01X304093Y-769672D02*
Y-844672D01*
G01X302093Y-769672D02*
Y-844672D01*
G01X304093Y-819672D02*
X504093D01*
G01X309726Y-804672D02*
Y-799672D01*
X311246D01*
X311753Y-799922D01*
X312133Y-800505D01*
X312260Y-801172D01*
X312133Y-801839D01*
X311816Y-802339D01*
X311246Y-802589D01*
X309726D01*
G01X314953Y-804839D02*
X317233Y-799672D01*
G01X319736Y-804672D02*
Y-799672D01*
X322650Y-804672D01*
Y-799672D01*
G01X326293Y-804839D02*
X326166Y-804755D01*
Y-804589D01*
X326293Y-804505D01*
X326420Y-804589D01*
Y-804755D01*
X326293Y-804839D01*
G01Y-802589D02*
X326166Y-802505D01*
Y-802339D01*
X326293Y-802255D01*
X326420Y-802339D01*
Y-802505D01*
X326293Y-802589D01*
G01X304093Y-794672D02*
X504093D01*
G01X309726Y-779672D02*
Y-774672D01*
X311246D01*
X311753Y-774922D01*
X312133Y-775505D01*
X312260Y-776172D01*
X312133Y-776839D01*
X311816Y-777339D01*
X311246Y-777589D01*
X309726D01*
G01X314826Y-779672D02*
Y-774672D01*
X316410D01*
X316916Y-774922D01*
X317233Y-775255D01*
X317360Y-775922D01*
X317233Y-776589D01*
X316853Y-777005D01*
X316410Y-777255D01*
X314826D01*
G01X316410D02*
X317360Y-779672D01*
G01X321193D02*
X320686Y-779589D01*
X320243Y-779255D01*
X319863Y-778755D01*
X319610Y-778172D01*
X319483Y-777505D01*
Y-776839D01*
X319610Y-776172D01*
X319863Y-775589D01*
X320243Y-775089D01*
X320686Y-774755D01*
X321193Y-774672D01*
X321700Y-774755D01*
X322143Y-775089D01*
X322523Y-775589D01*
X322776Y-776172D01*
X322903Y-776839D01*
Y-777505D01*
X322776Y-778172D01*
X322523Y-778755D01*
X322143Y-779255D01*
X321700Y-779589D01*
X321193Y-779672D01*
G01X325026Y-778672D02*
X325343Y-779172D01*
X325723Y-779505D01*
X326166Y-779672D01*
X326673Y-779505D01*
X327053Y-779172D01*
X327433Y-778672D01*
X327560Y-778005D01*
Y-774672D01*
G01X332660Y-779672D02*
X330126D01*
Y-774672D01*
X332660D01*
G01X331646Y-777089D02*
X330126D01*
G01X337886Y-775089D02*
X337506Y-774839D01*
X337063Y-774672D01*
X336556D01*
X335986Y-774922D01*
X335543Y-775339D01*
X335226Y-775839D01*
X334973Y-776672D01*
X334910Y-777422D01*
X335036Y-778172D01*
X335226Y-778672D01*
X335606Y-779172D01*
X336050Y-779505D01*
X336493Y-779672D01*
X336936D01*
X337380Y-779505D01*
X337760Y-779255D01*
X338076Y-778922D01*
G01X341593Y-774672D02*
Y-779672D01*
G01X340136Y-774672D02*
X343050D01*
G01X346693Y-779839D02*
X346566Y-779755D01*
Y-779589D01*
X346693Y-779505D01*
X346820Y-779589D01*
Y-779755D01*
X346693Y-779839D01*
G01Y-777589D02*
X346566Y-777505D01*
Y-777339D01*
X346693Y-777255D01*
X346820Y-777339D01*
Y-777505D01*
X346693Y-777589D01*
G01X419093Y-819672D02*
Y-844672D01*
G01X421726Y-822172D02*
Y-827172D01*
X424260D01*
G01X427333Y-822172D02*
X428853D01*
G01X428093D02*
Y-827172D01*
G01X427333D02*
X428853D01*
G01X433700Y-824505D02*
X433953Y-824255D01*
X434143Y-823839D01*
X434270Y-823255D01*
X434143Y-822755D01*
X433890Y-822422D01*
X433446Y-822172D01*
X431736D01*
Y-827172D01*
X433826D01*
X434270Y-826839D01*
X434523Y-826339D01*
X434650Y-825755D01*
X434523Y-825172D01*
X434143Y-824672D01*
X433700Y-824505D01*
X431736D01*
G01X438293Y-827339D02*
X438166Y-827255D01*
Y-827089D01*
X438293Y-827005D01*
X438420Y-827089D01*
Y-827255D01*
X438293Y-827339D01*
G01Y-825089D02*
X438166Y-825005D01*
Y-824839D01*
X438293Y-824755D01*
X438420Y-824839D01*
Y-825005D01*
X438293Y-825089D01*
G01X470106Y-847839D02*
X470213Y-847714D01*
X470293Y-847505D01*
X470346Y-847214D01*
X470293Y-846964D01*
X470186Y-846797D01*
X470000Y-846672D01*
X469280D01*
Y-849172D01*
X470160D01*
X470346Y-849005D01*
X470453Y-848755D01*
X470506Y-848464D01*
X470453Y-848172D01*
X470293Y-847922D01*
X470106Y-847839D01*
X469280D01*
G01X472573Y-849172D02*
Y-847505D01*
G01Y-847797D02*
X472466Y-847630D01*
X472306Y-847547D01*
X472120Y-847505D01*
X471933Y-847589D01*
X471773Y-847755D01*
X471666Y-848005D01*
X471613Y-848339D01*
X471666Y-848672D01*
X471773Y-848922D01*
X471933Y-849089D01*
X472120Y-849172D01*
X472306Y-849130D01*
X472466Y-849005D01*
X472573Y-848839D01*
G01X473893Y-848880D02*
X474026Y-849047D01*
X474213Y-849172D01*
X474373D01*
X474533Y-849089D01*
X474640Y-848964D01*
X474693Y-848797D01*
X474666Y-848547D01*
X474560Y-848422D01*
X474080Y-848172D01*
X473973Y-847880D01*
X474026Y-847672D01*
X474133Y-847547D01*
X474293Y-847505D01*
X474453Y-847547D01*
X474613Y-847672D01*
G01X476093Y-848047D02*
X476946D01*
X476866Y-847755D01*
X476733Y-847589D01*
X476546Y-847505D01*
X476360Y-847547D01*
X476200Y-847672D01*
X476093Y-847964D01*
X476040Y-848214D01*
Y-848464D01*
X476093Y-848714D01*
X476226Y-848964D01*
X476386Y-849130D01*
X476573Y-849172D01*
X476760Y-849089D01*
X476946Y-848839D01*
G01X478213Y-849172D02*
Y-846672D01*
G01Y-847922D02*
X478346Y-847672D01*
X478506Y-847547D01*
X478666Y-847505D01*
X478906Y-847589D01*
X479066Y-847755D01*
X479173Y-848047D01*
Y-848380D01*
X479120Y-848714D01*
X479013Y-848964D01*
X478826Y-849130D01*
X478666Y-849172D01*
X478506Y-849130D01*
X478346Y-849005D01*
X478213Y-848797D01*
G01X480893Y-849172D02*
X480733Y-849130D01*
X480573Y-848964D01*
X480466Y-848672D01*
X480413Y-848339D01*
X480466Y-848005D01*
X480573Y-847714D01*
X480733Y-847547D01*
X480893Y-847505D01*
X481053Y-847547D01*
X481213Y-847714D01*
X481320Y-848005D01*
X481346Y-848339D01*
X481320Y-848672D01*
X481213Y-848964D01*
X481053Y-849130D01*
X480893Y-849172D01*
G01X483573D02*
Y-847505D01*
G01Y-847797D02*
X483466Y-847630D01*
X483306Y-847547D01*
X483120Y-847505D01*
X482933Y-847589D01*
X482773Y-847755D01*
X482666Y-848005D01*
X482613Y-848339D01*
X482666Y-848672D01*
X482773Y-848922D01*
X482933Y-849089D01*
X483120Y-849172D01*
X483306Y-849130D01*
X483466Y-849005D01*
X483573Y-848839D01*
G01X484920Y-849172D02*
Y-847505D01*
G01Y-847839D02*
X485053Y-847672D01*
X485186Y-847547D01*
X485373Y-847505D01*
X485506Y-847547D01*
X485666Y-847672D01*
G01X487973Y-846672D02*
Y-849172D01*
G01Y-848797D02*
X487866Y-849005D01*
X487706Y-849130D01*
X487520Y-849172D01*
X487306Y-849089D01*
X487146Y-848880D01*
X487040Y-848630D01*
X487013Y-848339D01*
X487040Y-848047D01*
X487146Y-847797D01*
X487306Y-847589D01*
X487520Y-847505D01*
X487706Y-847547D01*
X487840Y-847630D01*
X487973Y-847797D01*
G01X491360Y-849172D02*
Y-846672D01*
X492026D01*
X492240Y-846797D01*
X492373Y-846964D01*
X492426Y-847297D01*
X492373Y-847630D01*
X492213Y-847839D01*
X492026Y-847964D01*
X491360D01*
G01X492026D02*
X492426Y-849172D01*
G01X493693Y-848047D02*
X494546D01*
X494466Y-847755D01*
X494333Y-847589D01*
X494146Y-847505D01*
X493960Y-847547D01*
X493800Y-847672D01*
X493693Y-847964D01*
X493640Y-848214D01*
Y-848464D01*
X493693Y-848714D01*
X493826Y-848964D01*
X493986Y-849130D01*
X494173Y-849172D01*
X494360Y-849089D01*
X494546Y-848839D01*
G01X495813Y-847505D02*
X496293Y-849172D01*
X496773Y-847505D01*
G01X498493Y-849255D02*
X498440Y-849214D01*
Y-849130D01*
X498493Y-849089D01*
X498546Y-849130D01*
Y-849214D01*
X498493Y-849255D01*
G01X500693Y-849172D02*
X500880Y-849130D01*
X501093Y-849005D01*
X501226Y-848797D01*
X501280Y-848505D01*
X501226Y-848214D01*
X501066Y-847964D01*
X500826Y-847839D01*
X500560D01*
X500400Y-847755D01*
X500266Y-847547D01*
X500213Y-847255D01*
X500293Y-846964D01*
X500480Y-846755D01*
X500693Y-846672D01*
X500906Y-846755D01*
X501093Y-846964D01*
X501173Y-847255D01*
X501120Y-847547D01*
X500986Y-847755D01*
X500826Y-847839D01*
X500560D01*
X500320Y-847964D01*
X500160Y-848214D01*
X500106Y-848505D01*
X500160Y-848797D01*
X500293Y-849005D01*
X500506Y-849130D01*
X500693Y-849172D01*
G01X503106Y-847839D02*
X503213Y-847714D01*
X503293Y-847505D01*
X503346Y-847214D01*
X503293Y-846964D01*
X503186Y-846797D01*
X503000Y-846672D01*
X502280D01*
Y-849172D01*
X503160D01*
X503346Y-849005D01*
X503453Y-848755D01*
X503506Y-848464D01*
X503453Y-848172D01*
X503293Y-847922D01*
X503106Y-847839D01*
X502280D01*
G01X465993Y-822172D02*
Y-827172D01*
G01X464536Y-822172D02*
X467450D01*
G01X471093Y-827172D02*
X470713Y-827089D01*
X470333Y-826755D01*
X470080Y-826172D01*
X469953Y-825505D01*
X470080Y-824839D01*
X470333Y-824255D01*
X470713Y-823922D01*
X471093Y-823839D01*
X471473Y-823922D01*
X471853Y-824255D01*
X472106Y-824839D01*
X472170Y-825505D01*
X472106Y-826172D01*
X471853Y-826755D01*
X471473Y-827089D01*
X471093Y-827172D01*
G01X476193D02*
X475813Y-827089D01*
X475433Y-826755D01*
X475180Y-826172D01*
X475053Y-825505D01*
X475180Y-824839D01*
X475433Y-824255D01*
X475813Y-823922D01*
X476193Y-823839D01*
X476573Y-823922D01*
X476953Y-824255D01*
X477206Y-824839D01*
X477270Y-825505D01*
X477206Y-826172D01*
X476953Y-826755D01*
X476573Y-827089D01*
X476193Y-827172D01*
G01X481293D02*
Y-822172D01*
G01X486393Y-827339D02*
X486266Y-827255D01*
Y-827089D01*
X486393Y-827005D01*
X486520Y-827089D01*
Y-827255D01*
X486393Y-827339D01*
G01Y-825089D02*
X486266Y-825005D01*
Y-824839D01*
X486393Y-824755D01*
X486520Y-824839D01*
Y-825005D01*
X486393Y-825089D01*
G01X462093Y-819672D02*
Y-844672D01*
G01Y-794672D02*
Y-819672D01*
G01X464726Y-802172D02*
Y-797172D01*
X466310D01*
X466816Y-797422D01*
X467133Y-797755D01*
X467260Y-798422D01*
X467133Y-799089D01*
X466753Y-799505D01*
X466310Y-799755D01*
X464726D01*
G01X466310D02*
X467260Y-802172D01*
G01X472360D02*
X469826D01*
Y-797172D01*
X472360D01*
G01X471346Y-799589D02*
X469826D01*
G01X474610Y-797172D02*
X476193Y-802172D01*
X477776Y-797172D01*
G01X481293Y-802339D02*
X481166Y-802255D01*
Y-802089D01*
X481293Y-802005D01*
X481420Y-802089D01*
Y-802255D01*
X481293Y-802339D01*
G01Y-800089D02*
X481166Y-800005D01*
Y-799839D01*
X481293Y-799755D01*
X481420Y-799839D01*
Y-800005D01*
X481293Y-800089D01*
G01X-297025Y-1013390D02*
Y1828909D01*
X3691357D01*
Y-1013390D01*
X-297025D01*
G01X16913Y-817022D02*
X18480D01*
Y-818912D01*
X18010Y-819542D01*
X17461Y-819962D01*
X16678Y-820172D01*
X15895Y-819962D01*
X15346Y-819542D01*
X14876Y-818912D01*
X14563Y-818177D01*
X14406Y-817337D01*
Y-816602D01*
X14563Y-815972D01*
X14876Y-815237D01*
X15346Y-814607D01*
X15816Y-814187D01*
X16443Y-813872D01*
X16991D01*
X17618Y-814082D01*
X18088Y-814502D01*
G01X21020Y-813872D02*
Y-818387D01*
X21333Y-819332D01*
X21960Y-819962D01*
X22743Y-820172D01*
X23526Y-819962D01*
X24153Y-819332D01*
X24466Y-818387D01*
Y-813872D01*
G01X28103D02*
X29983D01*
G01X29043D02*
Y-820172D01*
G01X28103D02*
X29983D01*
G01X33698Y-819332D02*
X34325Y-819857D01*
X35030Y-820172D01*
X35656D01*
X36283Y-819857D01*
X36753Y-819332D01*
X36988Y-818597D01*
X36831Y-817862D01*
X36440Y-817232D01*
X35735Y-816812D01*
X34795Y-816602D01*
X34246Y-816182D01*
X34011Y-815447D01*
X34168Y-814712D01*
X34560Y-814187D01*
X35108Y-813872D01*
X35656D01*
X36205Y-814082D01*
X36675Y-814607D01*
G01X39998Y-820172D02*
Y-813872D01*
G01X43288D02*
Y-820172D01*
G01Y-817022D02*
X39998D01*
G01X45985Y-820172D02*
X47943Y-813872D01*
X49901Y-820172D01*
G01X49196Y-817967D02*
X46690D01*
G01X52441Y-820172D02*
Y-813872D01*
X56045Y-820172D01*
Y-813872D01*
G01X65120Y-820172D02*
Y-813872D01*
X66686D01*
X67313Y-814187D01*
X67783Y-814607D01*
X68175Y-815237D01*
X68488Y-815972D01*
X68566Y-817022D01*
X68488Y-818072D01*
X68175Y-818807D01*
X67783Y-819437D01*
X67313Y-819857D01*
X66686Y-820172D01*
X65120D01*
G01X72203Y-813872D02*
X74083D01*
G01X73143D02*
Y-820172D01*
G01X72203D02*
X74083D01*
G01X77798Y-819332D02*
X78425Y-819857D01*
X79130Y-820172D01*
X79756D01*
X80383Y-819857D01*
X80853Y-819332D01*
X81088Y-818597D01*
X80931Y-817862D01*
X80540Y-817232D01*
X79835Y-816812D01*
X78895Y-816602D01*
X78346Y-816182D01*
X78111Y-815447D01*
X78268Y-814712D01*
X78660Y-814187D01*
X79208Y-813872D01*
X79756D01*
X80305Y-814082D01*
X80775Y-814607D01*
G01X85743Y-813872D02*
Y-820172D01*
G01X83941Y-813872D02*
X87545D01*
G01X92043Y-820382D02*
X91886Y-820277D01*
Y-820067D01*
X92043Y-819962D01*
X92200Y-820067D01*
Y-820277D01*
X92043Y-820382D01*
G01X98186Y-821327D02*
X98500Y-819962D01*
G01X104643Y-813872D02*
Y-820172D01*
G01X102841Y-813872D02*
X106445D01*
G01X108985Y-820172D02*
X110943Y-813872D01*
X112901Y-820172D01*
G01X112196Y-817967D02*
X109690D01*
G01X117243Y-820172D02*
X116616Y-820067D01*
X116068Y-819647D01*
X115598Y-819017D01*
X115285Y-818282D01*
X115128Y-817442D01*
Y-816602D01*
X115285Y-815762D01*
X115598Y-815027D01*
X116068Y-814397D01*
X116616Y-813977D01*
X117243Y-813872D01*
X117870Y-813977D01*
X118418Y-814397D01*
X118888Y-815027D01*
X119201Y-815762D01*
X119358Y-816602D01*
Y-817442D01*
X119201Y-818282D01*
X118888Y-819017D01*
X118418Y-819647D01*
X117870Y-820067D01*
X117243Y-820172D01*
G01X123543D02*
Y-817337D01*
X121976Y-813872D01*
G01X125110D02*
X123543Y-817337D01*
G01X128120Y-813872D02*
Y-818387D01*
X128433Y-819332D01*
X129060Y-819962D01*
X129843Y-820172D01*
X130626Y-819962D01*
X131253Y-819332D01*
X131566Y-818387D01*
Y-813872D01*
G01X134185Y-820172D02*
X136143Y-813872D01*
X138101Y-820172D01*
G01X137396Y-817967D02*
X134890D01*
G01X140641Y-820172D02*
Y-813872D01*
X144245Y-820172D01*
Y-813872D01*
G01X18166Y-824397D02*
X17696Y-824082D01*
X17148Y-823872D01*
X16521D01*
X15816Y-824187D01*
X15268Y-824712D01*
X14876Y-825342D01*
X14563Y-826392D01*
X14485Y-827337D01*
X14641Y-828282D01*
X14876Y-828912D01*
X15346Y-829542D01*
X15895Y-829962D01*
X16443Y-830172D01*
X16991D01*
X17540Y-829962D01*
X18010Y-829647D01*
X18401Y-829227D01*
G01X21803Y-823872D02*
X23683D01*
G01X22743D02*
Y-830172D01*
G01X21803D02*
X23683D01*
G01X29043Y-823872D02*
Y-830172D01*
G01X27241Y-823872D02*
X30845D01*
G01X35343Y-830172D02*
Y-827337D01*
X33776Y-823872D01*
G01X36910D02*
X35343Y-827337D01*
G01X46220Y-828912D02*
X46690Y-829647D01*
X47316Y-830067D01*
X48021Y-830172D01*
X48648Y-830067D01*
X49275Y-829542D01*
X49666Y-828912D01*
X49745Y-828282D01*
X49588Y-827547D01*
X49040Y-827022D01*
X48491Y-826812D01*
X47786D01*
G01X48491D02*
X48961Y-826497D01*
X49353Y-825972D01*
X49510Y-825342D01*
X49353Y-824712D01*
X48961Y-824187D01*
X48256Y-823872D01*
X47551Y-823977D01*
X46846Y-824397D01*
G01X52520Y-828912D02*
X52990Y-829647D01*
X53616Y-830067D01*
X54321Y-830172D01*
X54948Y-830067D01*
X55575Y-829542D01*
X55966Y-828912D01*
X56045Y-828282D01*
X55888Y-827547D01*
X55340Y-827022D01*
X54791Y-826812D01*
X54086D01*
G01X54791D02*
X55261Y-826497D01*
X55653Y-825972D01*
X55810Y-825342D01*
X55653Y-824712D01*
X55261Y-824187D01*
X54556Y-823872D01*
X53851Y-823977D01*
X53146Y-824397D01*
G01X58820Y-828912D02*
X59290Y-829647D01*
X59916Y-830067D01*
X60621Y-830172D01*
X61248Y-830067D01*
X61875Y-829542D01*
X62266Y-828912D01*
X62345Y-828282D01*
X62188Y-827547D01*
X61640Y-827022D01*
X61091Y-826812D01*
X60386D01*
G01X61091D02*
X61561Y-826497D01*
X61953Y-825972D01*
X62110Y-825342D01*
X61953Y-824712D01*
X61561Y-824187D01*
X60856Y-823872D01*
X60151Y-823977D01*
X59446Y-824397D01*
G01X66686Y-830172D02*
X66843Y-828807D01*
X67078Y-827652D01*
X67391Y-826602D01*
X67783Y-825447D01*
X68410Y-823872D01*
X65276D01*
G01X72986Y-830172D02*
X73143Y-828807D01*
X73378Y-827652D01*
X73691Y-826602D01*
X74083Y-825447D01*
X74710Y-823872D01*
X71576D01*
G01X79286Y-831327D02*
X79600Y-829962D01*
G01X85743Y-823872D02*
Y-830172D01*
G01X83941Y-823872D02*
X87545D01*
G01X90085Y-830172D02*
X92043Y-823872D01*
X94001Y-830172D01*
G01X93296Y-827967D02*
X90790D01*
G01X97403Y-823872D02*
X99283D01*
G01X98343D02*
Y-830172D01*
G01X97403D02*
X99283D01*
G01X102293Y-823872D02*
X103390Y-830172D01*
X104643Y-823872D01*
X105896Y-830172D01*
X106993Y-823872D01*
G01X108985Y-830172D02*
X110943Y-823872D01*
X112901Y-830172D01*
G01X112196Y-827967D02*
X109690D01*
G01X115441Y-830172D02*
Y-823872D01*
X119045Y-830172D01*
Y-823872D01*
G01X129451Y-832272D02*
X128668Y-831222D01*
X128276Y-830172D01*
Y-825972D01*
X128668Y-824922D01*
X129451Y-823872D01*
G01X140876Y-830172D02*
Y-823872D01*
X142835D01*
X143461Y-824187D01*
X143853Y-824607D01*
X144010Y-825447D01*
X143853Y-826287D01*
X143383Y-826812D01*
X142835Y-827127D01*
X140876D01*
G01X142835D02*
X144010Y-830172D01*
G01X148743Y-830382D02*
X148586Y-830277D01*
Y-830067D01*
X148743Y-829962D01*
X148900Y-830067D01*
Y-830277D01*
X148743Y-830382D01*
G01X155043Y-830172D02*
X154416Y-830067D01*
X153868Y-829647D01*
X153398Y-829017D01*
X153085Y-828282D01*
X152928Y-827442D01*
Y-826602D01*
X153085Y-825762D01*
X153398Y-825027D01*
X153868Y-824397D01*
X154416Y-823977D01*
X155043Y-823872D01*
X155670Y-823977D01*
X156218Y-824397D01*
X156688Y-825027D01*
X157001Y-825762D01*
X157158Y-826602D01*
Y-827442D01*
X157001Y-828282D01*
X156688Y-829017D01*
X156218Y-829647D01*
X155670Y-830067D01*
X155043Y-830172D01*
G01X161343Y-830382D02*
X161186Y-830277D01*
Y-830067D01*
X161343Y-829962D01*
X161500Y-830067D01*
Y-830277D01*
X161343Y-830382D01*
G01X169366Y-824397D02*
X168896Y-824082D01*
X168348Y-823872D01*
X167721D01*
X167016Y-824187D01*
X166468Y-824712D01*
X166076Y-825342D01*
X165763Y-826392D01*
X165685Y-827337D01*
X165841Y-828282D01*
X166076Y-828912D01*
X166546Y-829542D01*
X167095Y-829962D01*
X167643Y-830172D01*
X168191D01*
X168740Y-829962D01*
X169210Y-829647D01*
X169601Y-829227D01*
G01X173943Y-830382D02*
X173786Y-830277D01*
Y-830067D01*
X173943Y-829962D01*
X174100Y-830067D01*
Y-830277D01*
X173943Y-830382D01*
G01X180635Y-832272D02*
X181418Y-831222D01*
X181810Y-830172D01*
Y-825972D01*
X181418Y-824922D01*
X180635Y-823872D01*
G01X38743Y-799472D02*
X36223Y-799055D01*
X34018Y-797389D01*
X32128Y-794889D01*
X30868Y-791972D01*
X30238Y-788639D01*
Y-785305D01*
X30868Y-781972D01*
X32128Y-779055D01*
X34018Y-776556D01*
X36223Y-774889D01*
X38743Y-774472D01*
X41263Y-774889D01*
X43468Y-776556D01*
X45358Y-779055D01*
X46618Y-781972D01*
X47248Y-785305D01*
Y-788639D01*
X46618Y-791972D01*
X45358Y-794889D01*
X43468Y-797389D01*
X41263Y-799055D01*
X38743Y-799472D01*
G01X41263Y-792805D02*
X45043Y-799472D01*
G01X58588Y-782806D02*
Y-794472D01*
X59848Y-797389D01*
X61738Y-799055D01*
X63943Y-799472D01*
X66148Y-799055D01*
X68038Y-797389D01*
X69298Y-794472D01*
G01Y-799472D02*
Y-782806D01*
G01X94813Y-799472D02*
Y-782806D01*
G01Y-785722D02*
X93553Y-784056D01*
X91663Y-783222D01*
X89458Y-782806D01*
X87253Y-783639D01*
X85363Y-785305D01*
X84103Y-787806D01*
X83473Y-791139D01*
X84103Y-794472D01*
X85363Y-796973D01*
X87253Y-798639D01*
X89458Y-799472D01*
X91663Y-799055D01*
X93553Y-797806D01*
X94813Y-796139D01*
G01X108988Y-799472D02*
Y-782806D01*
G01Y-786972D02*
X110248Y-784889D01*
X112138Y-783222D01*
X114658Y-782806D01*
X116863Y-783222D01*
X118753Y-784889D01*
X119698Y-787806D01*
Y-799472D01*
G01X139543Y-774472D02*
Y-799472D01*
G01X135133Y-782806D02*
X143953D01*
G01X170413Y-799472D02*
Y-782806D01*
G01Y-785722D02*
X169153Y-784056D01*
X167263Y-783222D01*
X165058Y-782806D01*
X162853Y-783639D01*
X160963Y-785305D01*
X159703Y-787806D01*
X159073Y-791139D01*
X159703Y-794472D01*
X160963Y-796973D01*
X162853Y-798639D01*
X165058Y-799472D01*
X167263Y-799055D01*
X169153Y-797806D01*
X170413Y-796139D01*
G01X14641Y-810172D02*
Y-803872D01*
X18245Y-810172D01*
Y-803872D01*
G01X22743Y-810172D02*
X22116Y-810067D01*
X21568Y-809647D01*
X21098Y-809017D01*
X20785Y-808282D01*
X20628Y-807442D01*
Y-806602D01*
X20785Y-805762D01*
X21098Y-805027D01*
X21568Y-804397D01*
X22116Y-803977D01*
X22743Y-803872D01*
X23370Y-803977D01*
X23918Y-804397D01*
X24388Y-805027D01*
X24701Y-805762D01*
X24858Y-806602D01*
Y-807442D01*
X24701Y-808282D01*
X24388Y-809017D01*
X23918Y-809647D01*
X23370Y-810067D01*
X22743Y-810172D01*
G01X29043Y-810382D02*
X28886Y-810277D01*
Y-810067D01*
X29043Y-809962D01*
X29200Y-810067D01*
Y-810277D01*
X29043Y-810382D01*
G01X33855Y-804922D02*
X34325Y-804292D01*
X34873Y-803977D01*
X35500Y-803872D01*
X36283Y-804082D01*
X36831Y-804607D01*
X36988Y-805237D01*
X36910Y-805867D01*
X36596Y-806392D01*
X35030Y-807442D01*
X34325Y-808177D01*
X33855Y-809227D01*
X33698Y-810172D01*
X36988D01*
G01X41643D02*
Y-803872D01*
X40703Y-805132D01*
G01Y-810172D02*
X42583D01*
G01X47943D02*
Y-803872D01*
X47003Y-805132D01*
G01Y-810172D02*
X48883D01*
G01X54086Y-811327D02*
X54400Y-809962D01*
G01X58193Y-803872D02*
X59290Y-810172D01*
X60543Y-803872D01*
X61796Y-810172D01*
X62893Y-803872D01*
G01X68410Y-810172D02*
X65276D01*
Y-803872D01*
X68410D01*
G01X67156Y-806917D02*
X65276D01*
G01X71341Y-810172D02*
Y-803872D01*
X74945Y-810172D01*
Y-803872D01*
G01X77798Y-810172D02*
Y-803872D01*
G01X81088D02*
Y-810172D01*
G01Y-807022D02*
X77798D01*
G01X84020Y-803872D02*
Y-808387D01*
X84333Y-809332D01*
X84960Y-809962D01*
X85743Y-810172D01*
X86526Y-809962D01*
X87153Y-809332D01*
X87466Y-808387D01*
Y-803872D01*
G01X90085Y-810172D02*
X92043Y-803872D01*
X94001Y-810172D01*
G01X93296Y-807967D02*
X90790D01*
G01X103155Y-804922D02*
X103625Y-804292D01*
X104173Y-803977D01*
X104800Y-803872D01*
X105583Y-804082D01*
X106131Y-804607D01*
X106288Y-805237D01*
X106210Y-805867D01*
X105896Y-806392D01*
X104330Y-807442D01*
X103625Y-808177D01*
X103155Y-809227D01*
X102998Y-810172D01*
X106288D01*
G01X109141D02*
Y-803872D01*
X112745Y-810172D01*
Y-803872D01*
G01X115520Y-810172D02*
Y-803872D01*
X117086D01*
X117713Y-804187D01*
X118183Y-804607D01*
X118575Y-805237D01*
X118888Y-805972D01*
X118966Y-807022D01*
X118888Y-808072D01*
X118575Y-808807D01*
X118183Y-809437D01*
X117713Y-809857D01*
X117086Y-810172D01*
X115520D01*
G01X128276D02*
Y-803872D01*
X130235D01*
X130861Y-804187D01*
X131253Y-804607D01*
X131410Y-805447D01*
X131253Y-806287D01*
X130783Y-806812D01*
X130235Y-807127D01*
X128276D01*
G01X130235D02*
X131410Y-810172D01*
G01X134420D02*
Y-803872D01*
X135986D01*
X136613Y-804187D01*
X137083Y-804607D01*
X137475Y-805237D01*
X137788Y-805972D01*
X137866Y-807022D01*
X137788Y-808072D01*
X137475Y-808807D01*
X137083Y-809437D01*
X136613Y-809857D01*
X135986Y-810172D01*
X134420D01*
G01X142443Y-810382D02*
X142286Y-810277D01*
Y-810067D01*
X142443Y-809962D01*
X142600Y-810067D01*
Y-810277D01*
X142443Y-810382D01*
G01X210093Y-779172D02*
Y-787172D01*
X214093D01*
G01X221893D02*
Y-781839D01*
G01Y-782772D02*
X221493Y-782239D01*
X220893Y-781972D01*
X220193Y-781839D01*
X219493Y-782105D01*
X218893Y-782639D01*
X218493Y-783439D01*
X218293Y-784505D01*
X218493Y-785572D01*
X218893Y-786372D01*
X219493Y-786905D01*
X220193Y-787172D01*
X220893Y-787039D01*
X221493Y-786639D01*
X221893Y-786106D01*
G01X225993Y-789572D02*
X226593Y-789839D01*
X227393Y-789572D01*
X227893Y-789039D01*
X228293Y-788372D01*
X228893Y-786239D01*
X230193Y-781839D01*
G01X226993D02*
X228893Y-786239D01*
G01X234593Y-783572D02*
X237793D01*
X237493Y-782639D01*
X236993Y-782105D01*
X236293Y-781839D01*
X235593Y-781972D01*
X234993Y-782372D01*
X234593Y-783305D01*
X234393Y-784106D01*
Y-784905D01*
X234593Y-785705D01*
X235093Y-786505D01*
X235693Y-787039D01*
X236393Y-787172D01*
X237093Y-786905D01*
X237793Y-786106D01*
G01X242693Y-787172D02*
Y-781839D01*
G01Y-782905D02*
X243193Y-782372D01*
X243693Y-781972D01*
X244393Y-781839D01*
X244893Y-781972D01*
X245493Y-782372D01*
G01X229193Y-829172D02*
X232993D01*
X229193Y-837172D01*
X232993D01*
G01X239093Y-831839D02*
Y-837172D01*
G01Y-829705D02*
X238893Y-829572D01*
Y-829305D01*
X239093Y-829172D01*
X239293Y-829305D01*
Y-829572D01*
X239093Y-829705D01*
G01X245793Y-834505D02*
X248393D01*
G01X253093Y-837172D02*
Y-829172D01*
X255493D01*
X256293Y-829572D01*
X256893Y-830505D01*
X257093Y-831572D01*
X256893Y-832639D01*
X256393Y-833439D01*
X255493Y-833839D01*
X253093D01*
G01X263093Y-831839D02*
Y-837172D01*
G01Y-829705D02*
X262893Y-829572D01*
Y-829305D01*
X263093Y-829172D01*
X263293Y-829305D01*
Y-829572D01*
X263093Y-829705D01*
G01X269393Y-837172D02*
Y-831839D01*
G01Y-833172D02*
X269793Y-832505D01*
X270393Y-831972D01*
X271193Y-831839D01*
X271893Y-831972D01*
X272493Y-832505D01*
X272793Y-833439D01*
Y-837172D01*
G01X277693Y-839172D02*
X278393Y-839705D01*
X279193Y-839839D01*
X279893Y-839705D01*
X280493Y-839039D01*
X280893Y-838105D01*
Y-831839D01*
G01Y-832905D02*
X280493Y-832372D01*
X279893Y-831972D01*
X279193Y-831839D01*
X278393Y-832105D01*
X277893Y-832639D01*
X277493Y-833572D01*
X277293Y-834505D01*
X277393Y-835305D01*
X277793Y-836239D01*
X278393Y-836905D01*
X279193Y-837172D01*
X279793Y-837039D01*
X280493Y-836505D01*
X280893Y-835972D01*
G01X239893Y-804172D02*
X242293D01*
G01X241093D02*
Y-812172D01*
G01X239893D02*
X242293D01*
G01X246793D02*
Y-804172D01*
X251393Y-812172D01*
Y-804172D01*
G01X257093Y-812172D02*
Y-804172D01*
X255893Y-805772D01*
G01Y-812172D02*
X258293D01*
G01X261393Y-785572D02*
X261993Y-786505D01*
X262793Y-787039D01*
X263693Y-787172D01*
X264493Y-787039D01*
X265293Y-786372D01*
X265793Y-785572D01*
X265893Y-784772D01*
X265693Y-783839D01*
X264993Y-783172D01*
X264293Y-782905D01*
X263393D01*
G01X264293D02*
X264893Y-782505D01*
X265393Y-781839D01*
X265593Y-781039D01*
X265393Y-780239D01*
X264893Y-779572D01*
X263993Y-779172D01*
X263093Y-779305D01*
X262193Y-779839D01*
G01X336693Y-830505D02*
X337293Y-829705D01*
X337993Y-829305D01*
X338793Y-829172D01*
X339793Y-829439D01*
X340493Y-830105D01*
X340693Y-830905D01*
X340593Y-831706D01*
X340193Y-832372D01*
X338193Y-833705D01*
X337293Y-834639D01*
X336693Y-835972D01*
X336493Y-837172D01*
X340693D01*
G01X346593Y-829172D02*
X345793Y-829439D01*
X345193Y-830105D01*
X344793Y-830905D01*
X344493Y-831972D01*
X344393Y-833172D01*
X344493Y-834372D01*
X344793Y-835439D01*
X345193Y-836239D01*
X345793Y-836905D01*
X346593Y-837172D01*
X347393Y-836905D01*
X347993Y-836239D01*
X348393Y-835439D01*
X348693Y-834372D01*
X348793Y-833172D01*
X348693Y-831972D01*
X348393Y-830905D01*
X347993Y-830105D01*
X347393Y-829439D01*
X346593Y-829172D01*
G01X352693Y-830505D02*
X353293Y-829705D01*
X353993Y-829305D01*
X354793Y-829172D01*
X355793Y-829439D01*
X356493Y-830105D01*
X356693Y-830905D01*
X356593Y-831706D01*
X356193Y-832372D01*
X354193Y-833705D01*
X353293Y-834639D01*
X352693Y-835972D01*
X352493Y-837172D01*
X356693D01*
G01X360693Y-830505D02*
X361293Y-829705D01*
X361993Y-829305D01*
X362793Y-829172D01*
X363793Y-829439D01*
X364493Y-830105D01*
X364693Y-830905D01*
X364593Y-831706D01*
X364193Y-832372D01*
X362193Y-833705D01*
X361293Y-834639D01*
X360693Y-835972D01*
X360493Y-837172D01*
X364693D01*
G01X368793Y-837439D02*
X372393Y-829172D01*
G01X378593Y-837172D02*
Y-829172D01*
X377393Y-830772D01*
G01Y-837172D02*
X379793D01*
G01X384693Y-830505D02*
X385293Y-829705D01*
X385993Y-829305D01*
X386793Y-829172D01*
X387793Y-829439D01*
X388493Y-830105D01*
X388693Y-830905D01*
X388593Y-831706D01*
X388193Y-832372D01*
X386193Y-833705D01*
X385293Y-834639D01*
X384693Y-835972D01*
X384493Y-837172D01*
X388693D01*
G01X392793Y-837439D02*
X396393Y-829172D01*
G01X402593D02*
X401793Y-829439D01*
X401193Y-830105D01*
X400793Y-830905D01*
X400493Y-831972D01*
X400393Y-833172D01*
X400493Y-834372D01*
X400793Y-835439D01*
X401193Y-836239D01*
X401793Y-836905D01*
X402593Y-837172D01*
X403393Y-836905D01*
X403993Y-836239D01*
X404393Y-835439D01*
X404693Y-834372D01*
X404793Y-833172D01*
X404693Y-831972D01*
X404393Y-830905D01*
X403993Y-830105D01*
X403393Y-829439D01*
X402593Y-829172D01*
G01X408693Y-830505D02*
X409293Y-829705D01*
X409993Y-829305D01*
X410793Y-829172D01*
X411793Y-829439D01*
X412493Y-830105D01*
X412693Y-830905D01*
X412593Y-831706D01*
X412193Y-832372D01*
X410193Y-833705D01*
X409293Y-834639D01*
X408693Y-835972D01*
X408493Y-837172D01*
X412693D01*
G01X336393Y-814672D02*
Y-806672D01*
X338393D01*
X339193Y-807072D01*
X339793Y-807605D01*
X340293Y-808405D01*
X340693Y-809339D01*
X340793Y-810672D01*
X340693Y-812005D01*
X340293Y-812939D01*
X339793Y-813739D01*
X339193Y-814272D01*
X338393Y-814672D01*
X336393D01*
G01X344093D02*
X346593Y-806672D01*
X349093Y-814672D01*
G01X348193Y-811872D02*
X344993D01*
G01X354593Y-806672D02*
X353793Y-806939D01*
X353193Y-807605D01*
X352793Y-808405D01*
X352493Y-809472D01*
X352393Y-810672D01*
X352493Y-811872D01*
X352793Y-812939D01*
X353193Y-813739D01*
X353793Y-814405D01*
X354593Y-814672D01*
X355393Y-814405D01*
X355993Y-813739D01*
X356393Y-812939D01*
X356693Y-811872D01*
X356793Y-810672D01*
X356693Y-809472D01*
X356393Y-808405D01*
X355993Y-807605D01*
X355393Y-806939D01*
X354593Y-806672D01*
G01X360693Y-814672D02*
Y-806672D01*
X364493D01*
G01X363093Y-810539D02*
X360693D01*
G01X370593Y-806672D02*
X369793Y-806939D01*
X369193Y-807605D01*
X368793Y-808405D01*
X368493Y-809472D01*
X368393Y-810672D01*
X368493Y-811872D01*
X368793Y-812939D01*
X369193Y-813739D01*
X369793Y-814405D01*
X370593Y-814672D01*
X371393Y-814405D01*
X371993Y-813739D01*
X372393Y-812939D01*
X372693Y-811872D01*
X372793Y-810672D01*
X372693Y-809472D01*
X372393Y-808405D01*
X371993Y-807605D01*
X371393Y-806939D01*
X370593Y-806672D01*
G01X378593D02*
Y-814672D01*
G01X376293Y-806672D02*
X380893D01*
G01X384593Y-814672D02*
Y-806672D01*
X386993D01*
X387793Y-807072D01*
X388393Y-808005D01*
X388593Y-809072D01*
X388393Y-810139D01*
X387893Y-810939D01*
X386993Y-811339D01*
X384593D01*
G01X395393Y-810405D02*
X395793Y-810005D01*
X396093Y-809339D01*
X396293Y-808405D01*
X396093Y-807605D01*
X395693Y-807072D01*
X394993Y-806672D01*
X392293D01*
Y-814672D01*
X395593D01*
X396293Y-814139D01*
X396693Y-813339D01*
X396893Y-812405D01*
X396693Y-811472D01*
X396093Y-810672D01*
X395393Y-810405D01*
X392293D01*
G01X400093Y-814672D02*
X402593Y-806672D01*
X405093Y-814672D01*
G01X404193Y-811872D02*
X400993D01*
G01X408693Y-814672D02*
Y-806672D01*
X412493D01*
G01X411093Y-810539D02*
X408693D01*
G01X418593Y-806672D02*
X417793Y-806939D01*
X417193Y-807605D01*
X416793Y-808405D01*
X416493Y-809472D01*
X416393Y-810672D01*
X416493Y-811872D01*
X416793Y-812939D01*
X417193Y-813739D01*
X417793Y-814405D01*
X418593Y-814672D01*
X419393Y-814405D01*
X419993Y-813739D01*
X420393Y-812939D01*
X420693Y-811872D01*
X420793Y-810672D01*
X420693Y-809472D01*
X420393Y-808405D01*
X419993Y-807605D01*
X419393Y-806939D01*
X418593Y-806672D01*
G01X356693Y-787172D02*
Y-779172D01*
X360493D01*
G01X359093Y-783039D02*
X356693D01*
G01X366593Y-779172D02*
X365793Y-779439D01*
X365193Y-780105D01*
X364793Y-780905D01*
X364493Y-781972D01*
X364393Y-783172D01*
X364493Y-784372D01*
X364793Y-785439D01*
X365193Y-786239D01*
X365793Y-786905D01*
X366593Y-787172D01*
X367393Y-786905D01*
X367993Y-786239D01*
X368393Y-785439D01*
X368693Y-784372D01*
X368793Y-783172D01*
X368693Y-781972D01*
X368393Y-780905D01*
X367993Y-780105D01*
X367393Y-779439D01*
X366593Y-779172D01*
G01X374593D02*
Y-787172D01*
G01X372293Y-779172D02*
X376893D01*
G01X379593Y-789839D02*
X385593D01*
G01X388593Y-787172D02*
Y-779172D01*
X390993D01*
X391793Y-779572D01*
X392393Y-780505D01*
X392593Y-781572D01*
X392393Y-782639D01*
X391893Y-783439D01*
X390993Y-783839D01*
X388593D01*
G01X396393Y-787172D02*
Y-779172D01*
X398393D01*
X399193Y-779572D01*
X399793Y-780105D01*
X400293Y-780905D01*
X400693Y-781839D01*
X400793Y-783172D01*
X400693Y-784505D01*
X400293Y-785439D01*
X399793Y-786239D01*
X399193Y-786772D01*
X398393Y-787172D01*
X396393D01*
G01X407393Y-782905D02*
X407793Y-782505D01*
X408093Y-781839D01*
X408293Y-780905D01*
X408093Y-780105D01*
X407693Y-779572D01*
X406993Y-779172D01*
X404293D01*
Y-787172D01*
X407593D01*
X408293Y-786639D01*
X408693Y-785839D01*
X408893Y-784905D01*
X408693Y-783972D01*
X408093Y-783172D01*
X407393Y-782905D01*
X404293D01*
G01X411593Y-789839D02*
X417593D01*
G01X424793Y-779839D02*
X424193Y-779439D01*
X423493Y-779172D01*
X422693D01*
X421793Y-779572D01*
X421093Y-780239D01*
X420593Y-781039D01*
X420193Y-782372D01*
X420093Y-783572D01*
X420293Y-784772D01*
X420593Y-785572D01*
X421193Y-786372D01*
X421893Y-786905D01*
X422593Y-787172D01*
X423293D01*
X423993Y-786905D01*
X424593Y-786505D01*
X425093Y-785972D01*
G01X430593Y-787172D02*
X429793Y-787039D01*
X429093Y-786505D01*
X428493Y-785705D01*
X428093Y-784772D01*
X427893Y-783705D01*
Y-782639D01*
X428093Y-781572D01*
X428493Y-780639D01*
X429093Y-779839D01*
X429793Y-779305D01*
X430593Y-779172D01*
X431393Y-779305D01*
X432093Y-779839D01*
X432693Y-780639D01*
X433093Y-781572D01*
X433293Y-782639D01*
Y-783705D01*
X433093Y-784772D01*
X432693Y-785705D01*
X432093Y-786505D01*
X431393Y-787039D01*
X430593Y-787172D01*
G01X436293D02*
Y-779172D01*
X440893Y-787172D01*
Y-779172D01*
G01X444093D02*
X446593Y-787172D01*
X449093Y-779172D01*
G01X456593Y-787172D02*
X452593D01*
Y-779172D01*
X456593D01*
G01X454993Y-783039D02*
X452593D01*
G01X460593Y-787172D02*
Y-779172D01*
X463093D01*
X463893Y-779572D01*
X464393Y-780105D01*
X464593Y-781172D01*
X464393Y-782239D01*
X463793Y-782905D01*
X463093Y-783305D01*
X460593D01*
G01X463093D02*
X464593Y-787172D01*
G01X470593Y-779172D02*
Y-787172D01*
G01X468293Y-779172D02*
X472893D01*
G01X480593Y-787172D02*
X476593D01*
Y-779172D01*
X480593D01*
G01X478993Y-783039D02*
X476593D01*
G01X484593Y-787172D02*
Y-779172D01*
X487093D01*
X487893Y-779572D01*
X488393Y-780105D01*
X488593Y-781172D01*
X488393Y-782239D01*
X487793Y-782905D01*
X487093Y-783305D01*
X484593D01*
G01X487093D02*
X488593Y-787172D01*
G01X425093Y-840172D02*
Y-832172D01*
X423893Y-833772D01*
G01Y-840172D02*
X426293D01*
G01X431193Y-836839D02*
X431893Y-835905D01*
X432493Y-835372D01*
X433293Y-835105D01*
X433993Y-835372D01*
X434493Y-835905D01*
X434893Y-836705D01*
X434993Y-837639D01*
X434893Y-838439D01*
X434493Y-839239D01*
X433893Y-839905D01*
X433193Y-840172D01*
X432393Y-839905D01*
X431693Y-839106D01*
X431293Y-837905D01*
X431193Y-836572D01*
X431393Y-834839D01*
X431693Y-833905D01*
X432193Y-832972D01*
X432893Y-832305D01*
X433593Y-832172D01*
X434293Y-832439D01*
X434793Y-833105D01*
G01X441093Y-840439D02*
X440893Y-840305D01*
Y-840039D01*
X441093Y-839905D01*
X441293Y-840039D01*
Y-840305D01*
X441093Y-840439D01*
G01X447193Y-836839D02*
X447893Y-835905D01*
X448493Y-835372D01*
X449293Y-835105D01*
X449993Y-835372D01*
X450493Y-835905D01*
X450893Y-836705D01*
X450993Y-837639D01*
X450893Y-838439D01*
X450493Y-839239D01*
X449893Y-839905D01*
X449193Y-840172D01*
X448393Y-839905D01*
X447693Y-839106D01*
X447293Y-837905D01*
X447193Y-836572D01*
X447393Y-834839D01*
X447693Y-833905D01*
X448193Y-832972D01*
X448893Y-832305D01*
X449593Y-832172D01*
X450293Y-832439D01*
X450793Y-833105D01*
G01X470093Y-840172D02*
Y-832172D01*
X468893Y-833772D01*
G01Y-840172D02*
X471293D01*
G01X477893D02*
X478093Y-838439D01*
X478393Y-836972D01*
X478793Y-835639D01*
X479293Y-834172D01*
X480093Y-832172D01*
X476093D01*
G01X486093Y-840439D02*
X485893Y-840305D01*
Y-840039D01*
X486093Y-839905D01*
X486293Y-840039D01*
Y-840305D01*
X486093Y-840439D01*
G01X492193Y-833505D02*
X492793Y-832705D01*
X493493Y-832305D01*
X494293Y-832172D01*
X495293Y-832439D01*
X495993Y-833105D01*
X496193Y-833905D01*
X496093Y-834706D01*
X495693Y-835372D01*
X493693Y-836705D01*
X492793Y-837639D01*
X492193Y-838972D01*
X491993Y-840172D01*
X496193D01*
G01X490193Y-815172D02*
Y-807172D01*
X493993D01*
G01X492593Y-811039D02*
X490193D01*
G54D17*
X411752Y129685D03*
X401752D03*
X411752Y139685D03*
Y149685D03*
Y159685D03*
X401752Y139685D03*
Y149685D03*
Y159685D03*
X446752Y129685D03*
X436752D03*
X446752Y139685D03*
Y149685D03*
Y159685D03*
X436752Y139685D03*
Y149685D03*
Y159685D03*
X481752Y129685D03*
X471752D03*
X481752Y139685D03*
Y149685D03*
Y159685D03*
X471752Y139685D03*
Y149685D03*
Y159685D03*
X712559Y129408D03*
Y119408D03*
Y149408D03*
Y139408D03*
X722559Y129408D03*
Y119408D03*
X747559Y129408D03*
Y119408D03*
X722559Y149408D03*
Y139408D03*
X747559Y149408D03*
Y139408D03*
X757559Y129408D03*
Y119408D03*
Y149408D03*
Y139408D03*
X782559Y129408D03*
Y119408D03*
X792559Y129408D03*
Y119408D03*
X782559Y149408D03*
Y139408D03*
X792559Y149408D03*
Y139408D03*
X812559D03*
X852559Y129408D03*
Y119408D03*
X862559Y129408D03*
Y119408D03*
X852559Y149408D03*
Y139408D03*
X862559Y149408D03*
Y139408D03*
X887559Y129408D03*
Y119408D03*
Y149408D03*
Y139408D03*
X897559Y129408D03*
Y119408D03*
X922559Y129408D03*
Y119408D03*
X897559Y149408D03*
Y139408D03*
X922559Y149408D03*
Y139408D03*
X932559Y129408D03*
Y119408D03*
Y149408D03*
Y139408D03*
X1226024Y221929D03*
X1236024D03*
X1246024D03*
X1226024Y231929D03*
X1236024D03*
X1246024D03*
X1226024Y256929D03*
X1236024D03*
X1246024D03*
X1226024Y266929D03*
X1236024D03*
X1246024D03*
X1226024Y306929D03*
X1236024D03*
X1246024D03*
X1226024Y316929D03*
X1236024D03*
X1246024D03*
X1226024Y341929D03*
X1236024D03*
X1246024D03*
X1226024Y351929D03*
X1236024D03*
X1246024D03*
X1256024Y221929D03*
Y231929D03*
Y256929D03*
Y266929D03*
Y306929D03*
Y316929D03*
Y341929D03*
Y351929D03*
G54D27*
G01X161400Y323200D02*
Y248001D01*
X166068Y243333D01*
Y238749D01*
G01X766498Y612542D02*
X1061384D01*
X1061894Y612032D01*
Y603052D01*
X1061384Y602542D01*
X766498D01*
G54D18*
D03*
Y612542D03*
G54D19*
X860237Y47244D03*
M02*
